FILE_TYPE = MACRO_DRAWING;
SET COLOR_WIRE YELLOW;
SET COLOR_PROP ORANGE;
SET COLOR_DOT WHITE;
SET COLOR_ARC YELLOW;
SET COLOR_BODY GREEN;
SET COLOR_NOTE PURPLE;
SET PROP_DISPLAY VALUE;
SET PAGE_NUMBER P418;
FORCEADD OFFPAGE..1
(-4200 1975);
FORCEPROP 2 LAST $XR0 298 
J 0
(-4482 1975);
DISPLAY 0.638298 (-4482 1975);
PAINT MONO (-4482 1975);
FORCEPROP 2 LAST CDS_LIB standard
J 0
(-4200 1975);
DISPLAY INVISIBLE (-4200 1975);
FORCEPROP 1 LAST OFFPAGE TRUE
J 0
(-3875 1850);
DISPLAY 0.872340 (-3875 1850);
DISPLAY INVISIBLE (-3875 1850);
FORCEPROP 1 LAST COMMENT_BODY TRUE
J 0
(-4075 1875);
DISPLAY 0.872340 (-4075 1875);
PAINT GREEN (-4075 1875);
DISPLAY INVISIBLE (-4075 1875);
FORCEPROP 2 LAST PATH I1
J 0
(-4450 2025);
DISPLAY 0.680851 (-4450 2025);
DISPLAY INVISIBLE (-4450 2025);
FORCEADD TAP..1
R 2
(-3250 1500);
FORCEPROP 3 LASTPIN (-3200 1500) SIG_NAME P5E_CPU0_P2_TX_BUF_DN<2>
J 0
(-3190 1510);
DISPLAY 0.659574 (-3190 1510);
PAINT MONO (-3190 1510);
DISPLAY INVISIBLE (-3190 1510);
FORCEPROP 1 LASTPIN (-3200 1500) BN 2
J 2
(-3188 1508);
DISPLAY 0.680851 (-3188 1508);
PAINT GREEN (-3188 1508);
FORCEPROP 2 LAST CDS_LIB standard
J 0
(-3250 1500);
DISPLAY INVISIBLE (-3250 1500);
FORCEPROP 1 LAST BODY_TYPE PLUMBING
J 2
(-3250 1550);
DISPLAY 0.872340 (-3250 1550);
PAINT GREEN (-3250 1550);
DISPLAY INVISIBLE (-3250 1550);
FORCEPROP 1 LAST HDL_TAP TRUE
J 2
(-3575 1375);
DISPLAY 0.872340 (-3575 1375);
DISPLAY INVISIBLE (-3575 1375);
FORCEPROP 1 LAST PATH I10
J 2
(-3248 1500);
DISPLAY 0.872340 (-3248 1500);
PAINT GREEN (-3248 1500);
DISPLAY INVISIBLE (-3248 1500);
FORCEADD Q_CAP_DIFFBUS..2
R 2
(-7125 1775);
FORCEPROP 1 LAST LOCATION C6584
J 2
(-6850 1775);
DISPLAY 0.723404 (-6850 1775);
PAINT GREEN (-6850 1775);
FORCEPROP 2 LAST $SEC 1
J 2
(-6950 1850);
DISPLAY 0.680851 (-6950 1850);
PAINT MONO (-6950 1850);
DISPLAY INVISIBLE (-6950 1850);
FORCEPROP 2 LAST CDS_SEC 1
J 2
(-6950 1850);
DISPLAY 0.680851 (-6950 1850);
DISPLAY INVISIBLE (-6950 1850);
FORCEPROP 2 LASTPIN (-7050 1775) $PN 1
J 0
(-7040 1785);
DISPLAY 0.808511 (-7040 1785);
FORCEPROP 2 LASTPIN (-7200 1775) $PN 2
J 2
(-7210 1785);
DISPLAY 0.808511 (-7210 1785);
FORCEPROP 2 LAST VALUE DIFF BUS_0.22UF
J 2
(-7275 1775);
DISPLAY 0.553191 (-7275 1775);
FORCEPROP 2 LAST TOLERANCE 20%
J 2
(-7200 1825);
DISPLAY 0.553191 (-7200 1825);
DISPLAY INVISIBLE (-7200 1825);
FORCEPROP 2 LAST PACK_TYPE C0201
J 2
(-7300 1825);
DISPLAY 0.553191 (-7300 1825);
DISPLAY INVISIBLE (-7300 1825);
FORCEPROP 1 LAST MATERIAL X6S
J 2
(-7116 1854);
DISPLAY 0.574468 (-7116 1854);
PAINT GREEN (-7116 1854);
DISPLAY INVISIBLE (-7116 1854);
FORCEPROP 2 LAST VOLTAGE 6.3V
J 2
(-7475 1825);
DISPLAY 0.553191 (-7475 1825);
DISPLAY INVISIBLE (-7475 1825);
FORCEPROP 1 LAST PIN_NAMES_ROTATE TRUE
J 2
(-7125 1775);
DISPLAY 0.489362 (-7125 1775);
PAINT GREEN (-7125 1775);
DISPLAY INVISIBLE (-7125 1775);
FORCEPROP 2 LAST CDS_LIB pure_quanta
J 2
(-7125 1775);
DISPLAY INVISIBLE (-7125 1775);
FORCEPROP 1 LAST CDS_LMAN_SYM_OUTLINE -25,50,25,-50
J 2
(-7125 1775);
DISPLAY 0.468085 (-7125 1775);
PAINT GREEN (-7125 1775);
DISPLAY INVISIBLE (-7125 1775);
FORCEPROP 1 LAST PATH I100
J 2
(-7125 1775);
DISPLAY 0.723404 (-7125 1775);
DISPLAY INVISIBLE (-7125 1775);
FORCEPROP 1 LAST PART_NUMBER SP_CH4221MEE01
J 2
(-7241 1863);
DISPLAY 0.574468 (-7241 1863);
PAINT GREEN (-7241 1863);
DISPLAY INVISIBLE (-7241 1863);
FORCEPROP 1 LAST LOCATION C6584
J 0
(-6875 1850);
DISPLAY 1.021277 (-6875 1850);
DISPLAY INVISIBLE (-6875 1850);
FORCEADD Q_CAP_DIFFBUS..2
R 2
(-7125 1825);
FORCEPROP 1 LAST LOCATION C6583
J 2
(-6850 1825);
DISPLAY 0.723404 (-6850 1825);
PAINT GREEN (-6850 1825);
FORCEPROP 2 LAST $SEC 1
J 2
(-6950 1900);
DISPLAY 0.680851 (-6950 1900);
PAINT MONO (-6950 1900);
DISPLAY INVISIBLE (-6950 1900);
FORCEPROP 2 LAST CDS_SEC 1
J 2
(-6950 1900);
DISPLAY 0.680851 (-6950 1900);
DISPLAY INVISIBLE (-6950 1900);
FORCEPROP 2 LASTPIN (-7050 1825) $PN 1
J 0
(-7040 1835);
DISPLAY 0.808511 (-7040 1835);
FORCEPROP 2 LASTPIN (-7200 1825) $PN 2
J 2
(-7210 1835);
DISPLAY 0.808511 (-7210 1835);
FORCEPROP 2 LAST VALUE DIFF BUS_0.22UF
J 2
(-7275 1825);
DISPLAY 0.553191 (-7275 1825);
FORCEPROP 2 LAST TOLERANCE 20%
J 2
(-7200 1875);
DISPLAY 0.553191 (-7200 1875);
DISPLAY INVISIBLE (-7200 1875);
FORCEPROP 2 LAST PACK_TYPE C0201
J 2
(-7300 1875);
DISPLAY 0.553191 (-7300 1875);
DISPLAY INVISIBLE (-7300 1875);
FORCEPROP 1 LAST MATERIAL X6S
J 2
(-7116 1904);
DISPLAY 0.574468 (-7116 1904);
PAINT GREEN (-7116 1904);
DISPLAY INVISIBLE (-7116 1904);
FORCEPROP 2 LAST VOLTAGE 6.3V
J 2
(-7475 1875);
DISPLAY 0.553191 (-7475 1875);
DISPLAY INVISIBLE (-7475 1875);
FORCEPROP 1 LAST PIN_NAMES_ROTATE TRUE
J 2
(-7125 1825);
DISPLAY 0.489362 (-7125 1825);
PAINT GREEN (-7125 1825);
DISPLAY INVISIBLE (-7125 1825);
FORCEPROP 2 LAST CDS_LIB pure_quanta
J 2
(-7125 1825);
DISPLAY INVISIBLE (-7125 1825);
FORCEPROP 1 LAST CDS_LMAN_SYM_OUTLINE -25,50,25,-50
J 2
(-7125 1825);
DISPLAY 0.468085 (-7125 1825);
PAINT GREEN (-7125 1825);
DISPLAY INVISIBLE (-7125 1825);
FORCEPROP 1 LAST PATH I101
J 2
(-7125 1825);
DISPLAY 0.723404 (-7125 1825);
DISPLAY INVISIBLE (-7125 1825);
FORCEPROP 1 LAST PART_NUMBER SP_CH4221MEE01
J 2
(-7241 1913);
DISPLAY 0.574468 (-7241 1913);
PAINT GREEN (-7241 1913);
DISPLAY INVISIBLE (-7241 1913);
FORCEPROP 1 LAST LOCATION C6583
J 0
(-6875 1900);
DISPLAY 1.021277 (-6875 1900);
DISPLAY INVISIBLE (-6875 1900);
FORCEADD TAP..1
R 2
(-8100 1975);
FORCEPROP 3 LASTPIN (-8050 1975) SIG_NAME P5E_CPU0_P2_TX_BUF_DN<8>
J 0
(-8040 1985);
DISPLAY 0.659574 (-8040 1985);
PAINT MONO (-8040 1985);
DISPLAY INVISIBLE (-8040 1985);
FORCEPROP 1 LASTPIN (-8050 1975) BN 8
J 2
(-8038 1983);
DISPLAY 0.680851 (-8038 1983);
PAINT GREEN (-8038 1983);
FORCEPROP 2 LAST CDS_LIB standard
J 0
(-8100 1975);
DISPLAY INVISIBLE (-8100 1975);
FORCEPROP 1 LAST BODY_TYPE PLUMBING
J 2
(-8100 2025);
DISPLAY 0.872340 (-8100 2025);
PAINT GREEN (-8100 2025);
DISPLAY INVISIBLE (-8100 2025);
FORCEPROP 1 LAST HDL_TAP TRUE
J 2
(-8425 1850);
DISPLAY 0.872340 (-8425 1850);
DISPLAY INVISIBLE (-8425 1850);
FORCEPROP 1 LAST PATH I102
J 2
(-8098 1975);
DISPLAY 0.872340 (-8098 1975);
PAINT GREEN (-8098 1975);
DISPLAY INVISIBLE (-8098 1975);
FORCEADD TAP..1
R 2
(-7850 2025);
FORCEPROP 3 LASTPIN (-7800 2025) SIG_NAME P5E_CPU0_P2_TX_BUF_DP<8>
J 0
(-7790 2035);
DISPLAY 0.659574 (-7790 2035);
PAINT MONO (-7790 2035);
DISPLAY INVISIBLE (-7790 2035);
FORCEPROP 1 LASTPIN (-7800 2025) BN 8
J 2
(-7788 2033);
DISPLAY 0.680851 (-7788 2033);
PAINT GREEN (-7788 2033);
FORCEPROP 2 LAST CDS_LIB standard
J 0
(-7850 2025);
DISPLAY INVISIBLE (-7850 2025);
FORCEPROP 1 LAST BODY_TYPE PLUMBING
J 2
(-7850 2075);
DISPLAY 0.872340 (-7850 2075);
PAINT GREEN (-7850 2075);
DISPLAY INVISIBLE (-7850 2075);
FORCEPROP 1 LAST HDL_TAP TRUE
J 2
(-8175 1900);
DISPLAY 0.872340 (-8175 1900);
DISPLAY INVISIBLE (-8175 1900);
FORCEPROP 1 LAST PATH I103
J 2
(-7848 2025);
DISPLAY 0.872340 (-7848 2025);
PAINT GREEN (-7848 2025);
DISPLAY INVISIBLE (-7848 2025);
FORCEADD Q_CAP_DIFFBUS..2
R 2
(-7125 2025);
FORCEPROP 1 LAST LOCATION C6581
J 2
(-6850 2025);
DISPLAY 0.723404 (-6850 2025);
PAINT GREEN (-6850 2025);
FORCEPROP 2 LAST $SEC 1
J 2
(-6950 2100);
DISPLAY 0.680851 (-6950 2100);
PAINT MONO (-6950 2100);
DISPLAY INVISIBLE (-6950 2100);
FORCEPROP 2 LAST CDS_SEC 1
J 2
(-6950 2100);
DISPLAY 0.680851 (-6950 2100);
DISPLAY INVISIBLE (-6950 2100);
FORCEPROP 2 LASTPIN (-7050 2025) $PN 1
J 0
(-7040 2035);
DISPLAY 0.808511 (-7040 2035);
FORCEPROP 2 LASTPIN (-7200 2025) $PN 2
J 2
(-7210 2035);
DISPLAY 0.808511 (-7210 2035);
FORCEPROP 2 LAST TOLERANCE 20%
J 2
(-7075 2175);
DISPLAY 0.553191 (-7075 2175);
PAINT GREEN (-7075 2175);
FORCEPROP 1 LAST MATERIAL X6S
J 2
(-7216 2229);
DISPLAY 0.574468 (-7216 2229);
PAINT GREEN (-7216 2229);
FORCEPROP 2 LAST PACK_TYPE C0201
J 2
(-7175 2175);
DISPLAY 0.553191 (-7175 2175);
PAINT GREEN (-7175 2175);
FORCEPROP 2 LAST VOLTAGE 6.3V
J 2
(-6950 2175);
DISPLAY 0.553191 (-6950 2175);
PAINT GREEN (-6950 2175);
FORCEPROP 2 LAST VALUE DIFF BUS_0.22UF
J 2
(-7275 2025);
DISPLAY 0.553191 (-7275 2025);
FORCEPROP 1 LAST PIN_NAMES_ROTATE TRUE
J 2
(-7125 2025);
DISPLAY 0.489362 (-7125 2025);
PAINT GREEN (-7125 2025);
DISPLAY INVISIBLE (-7125 2025);
FORCEPROP 1 LAST CDS_LMAN_SYM_OUTLINE -25,50,25,-50
J 2
(-7125 2025);
DISPLAY 0.468085 (-7125 2025);
PAINT GREEN (-7125 2025);
DISPLAY INVISIBLE (-7125 2025);
FORCEPROP 2 LAST CDS_LIB pure_quanta
J 2
(-7125 2025);
DISPLAY INVISIBLE (-7125 2025);
FORCEPROP 1 LAST PATH I104
J 2
(-7125 2025);
DISPLAY 0.723404 (-7125 2025);
DISPLAY INVISIBLE (-7125 2025);
FORCEPROP 1 LAST PART_NUMBER SP_CH4221MEE01
J 2
(-6941 2113);
DISPLAY 0.574468 (-6941 2113);
PAINT GREEN (-6941 2113);
DISPLAY INVISIBLE (-6941 2113);
FORCEPROP 1 LAST LOCATION C6581
J 0
(-6875 2100);
DISPLAY 1.021277 (-6875 2100);
DISPLAY INVISIBLE (-6875 2100);
FORCEADD Q_CAP_DIFFBUS..2
R 2
(-7125 1975);
FORCEPROP 1 LAST LOCATION C6582
J 2
(-6850 1975);
DISPLAY 0.723404 (-6850 1975);
PAINT GREEN (-6850 1975);
FORCEPROP 2 LAST $SEC 1
J 2
(-6950 2050);
DISPLAY 0.680851 (-6950 2050);
PAINT MONO (-6950 2050);
DISPLAY INVISIBLE (-6950 2050);
FORCEPROP 2 LAST CDS_SEC 1
J 2
(-6950 2050);
DISPLAY 0.680851 (-6950 2050);
DISPLAY INVISIBLE (-6950 2050);
FORCEPROP 2 LASTPIN (-7050 1975) $PN 1
J 0
(-7040 1985);
DISPLAY 0.808511 (-7040 1985);
FORCEPROP 2 LASTPIN (-7200 1975) $PN 2
J 2
(-7210 1985);
DISPLAY 0.808511 (-7210 1985);
FORCEPROP 2 LAST VALUE DIFF BUS_0.22UF
J 2
(-7275 1975);
DISPLAY 0.553191 (-7275 1975);
FORCEPROP 2 LAST TOLERANCE 20%
J 2
(-7200 2025);
DISPLAY 0.553191 (-7200 2025);
DISPLAY INVISIBLE (-7200 2025);
FORCEPROP 2 LAST PACK_TYPE C0201
J 2
(-7300 2025);
DISPLAY 0.553191 (-7300 2025);
DISPLAY INVISIBLE (-7300 2025);
FORCEPROP 1 LAST MATERIAL X6S
J 2
(-7116 2054);
DISPLAY 0.574468 (-7116 2054);
PAINT GREEN (-7116 2054);
DISPLAY INVISIBLE (-7116 2054);
FORCEPROP 2 LAST VOLTAGE 6.3V
J 2
(-7475 2025);
DISPLAY 0.553191 (-7475 2025);
DISPLAY INVISIBLE (-7475 2025);
FORCEPROP 1 LAST PIN_NAMES_ROTATE TRUE
J 2
(-7125 1975);
DISPLAY 0.489362 (-7125 1975);
PAINT GREEN (-7125 1975);
DISPLAY INVISIBLE (-7125 1975);
FORCEPROP 2 LAST CDS_LIB pure_quanta
J 2
(-7125 1975);
DISPLAY INVISIBLE (-7125 1975);
FORCEPROP 1 LAST CDS_LMAN_SYM_OUTLINE -25,50,25,-50
J 2
(-7125 1975);
DISPLAY 0.468085 (-7125 1975);
PAINT GREEN (-7125 1975);
DISPLAY INVISIBLE (-7125 1975);
FORCEPROP 1 LAST PATH I105
J 2
(-7125 1975);
DISPLAY 0.723404 (-7125 1975);
DISPLAY INVISIBLE (-7125 1975);
FORCEPROP 1 LAST PART_NUMBER SP_CH4221MEE01
J 2
(-7241 2063);
DISPLAY 0.574468 (-7241 2063);
PAINT GREEN (-7241 2063);
DISPLAY INVISIBLE (-7241 2063);
FORCEPROP 1 LAST LOCATION C6582
J 0
(-6875 2050);
DISPLAY 1.021277 (-6875 2050);
DISPLAY INVISIBLE (-6875 2050);
FORCEADD TAP..1
(-6575 625);
FORCEPROP 3 LASTPIN (-6625 625) SIG_NAME P5E_CPU0_P2_TX_BUF_C_DP<15>
J 0
(-6615 635);
DISPLAY 0.659574 (-6615 635);
PAINT MONO (-6615 635);
DISPLAY INVISIBLE (-6615 635);
FORCEPROP 1 LASTPIN (-6625 625) BN 15
J 0
(-6637 633);
DISPLAY 0.680851 (-6637 633);
PAINT GREEN (-6637 633);
FORCEPROP 2 LAST CDS_LIB standard
J 0
(-6575 625);
DISPLAY INVISIBLE (-6575 625);
FORCEPROP 1 LAST BODY_TYPE PLUMBING
J 0
(-6575 675);
DISPLAY 0.872340 (-6575 675);
PAINT GREEN (-6575 675);
DISPLAY INVISIBLE (-6575 675);
FORCEPROP 1 LAST HDL_TAP TRUE
J 0
(-6250 500);
DISPLAY 0.872340 (-6250 500);
DISPLAY INVISIBLE (-6250 500);
FORCEPROP 1 LAST PATH I106
J 0
(-6577 625);
DISPLAY 0.872340 (-6577 625);
PAINT GREEN (-6577 625);
DISPLAY INVISIBLE (-6577 625);
FORCEADD TAP..1
(-6575 825);
FORCEPROP 3 LASTPIN (-6625 825) SIG_NAME P5E_CPU0_P2_TX_BUF_C_DP<14>
J 0
(-6615 835);
DISPLAY 0.659574 (-6615 835);
PAINT MONO (-6615 835);
DISPLAY INVISIBLE (-6615 835);
FORCEPROP 1 LASTPIN (-6625 825) BN 14
J 0
(-6637 833);
DISPLAY 0.680851 (-6637 833);
PAINT GREEN (-6637 833);
FORCEPROP 2 LAST CDS_LIB standard
J 0
(-6575 825);
DISPLAY INVISIBLE (-6575 825);
FORCEPROP 1 LAST BODY_TYPE PLUMBING
J 0
(-6575 875);
DISPLAY 0.872340 (-6575 875);
PAINT GREEN (-6575 875);
DISPLAY INVISIBLE (-6575 875);
FORCEPROP 1 LAST HDL_TAP TRUE
J 0
(-6250 700);
DISPLAY 0.872340 (-6250 700);
DISPLAY INVISIBLE (-6250 700);
FORCEPROP 1 LAST PATH I107
J 0
(-6577 825);
DISPLAY 0.872340 (-6577 825);
PAINT GREEN (-6577 825);
DISPLAY INVISIBLE (-6577 825);
FORCEADD TAP..1
(-6375 575);
FORCEPROP 3 LASTPIN (-6425 575) SIG_NAME P5E_CPU0_P2_TX_BUF_C_DN<15>
J 0
(-6415 585);
DISPLAY 0.659574 (-6415 585);
PAINT MONO (-6415 585);
DISPLAY INVISIBLE (-6415 585);
FORCEPROP 1 LASTPIN (-6425 575) BN 15
J 0
(-6437 583);
DISPLAY 0.680851 (-6437 583);
PAINT GREEN (-6437 583);
FORCEPROP 2 LAST CDS_LIB standard
J 0
(-6375 575);
DISPLAY INVISIBLE (-6375 575);
FORCEPROP 1 LAST BODY_TYPE PLUMBING
J 0
(-6375 625);
DISPLAY 0.872340 (-6375 625);
PAINT GREEN (-6375 625);
DISPLAY INVISIBLE (-6375 625);
FORCEPROP 1 LAST HDL_TAP TRUE
J 0
(-6050 450);
DISPLAY 0.872340 (-6050 450);
DISPLAY INVISIBLE (-6050 450);
FORCEPROP 1 LAST PATH I108
J 0
(-6377 575);
DISPLAY 0.872340 (-6377 575);
PAINT GREEN (-6377 575);
DISPLAY INVISIBLE (-6377 575);
FORCEADD TAP..1
(-6375 775);
FORCEPROP 3 LASTPIN (-6425 775) SIG_NAME P5E_CPU0_P2_TX_BUF_C_DN<14>
J 0
(-6415 785);
DISPLAY 0.659574 (-6415 785);
PAINT MONO (-6415 785);
DISPLAY INVISIBLE (-6415 785);
FORCEPROP 1 LASTPIN (-6425 775) BN 14
J 0
(-6437 783);
DISPLAY 0.680851 (-6437 783);
PAINT GREEN (-6437 783);
FORCEPROP 2 LAST CDS_LIB standard
J 0
(-6375 775);
DISPLAY INVISIBLE (-6375 775);
FORCEPROP 1 LAST BODY_TYPE PLUMBING
J 0
(-6375 825);
DISPLAY 0.872340 (-6375 825);
PAINT GREEN (-6375 825);
DISPLAY INVISIBLE (-6375 825);
FORCEPROP 1 LAST HDL_TAP TRUE
J 0
(-6050 650);
DISPLAY 0.872340 (-6050 650);
DISPLAY INVISIBLE (-6050 650);
FORCEPROP 1 LAST PATH I109
J 0
(-6377 775);
DISPLAY 0.872340 (-6377 775);
PAINT GREEN (-6377 775);
DISPLAY INVISIBLE (-6377 775);
FORCEADD TAP..1
R 2
(-3250 1700);
FORCEPROP 3 LASTPIN (-3200 1700) SIG_NAME P5E_CPU0_P2_TX_BUF_DN<1>
J 0
(-3190 1710);
DISPLAY 0.659574 (-3190 1710);
PAINT MONO (-3190 1710);
DISPLAY INVISIBLE (-3190 1710);
FORCEPROP 1 LASTPIN (-3200 1700) BN 1
J 2
(-3188 1708);
DISPLAY 0.680851 (-3188 1708);
PAINT GREEN (-3188 1708);
FORCEPROP 2 LAST CDS_LIB standard
J 0
(-3250 1700);
DISPLAY INVISIBLE (-3250 1700);
FORCEPROP 1 LAST BODY_TYPE PLUMBING
J 2
(-3250 1750);
DISPLAY 0.872340 (-3250 1750);
PAINT GREEN (-3250 1750);
DISPLAY INVISIBLE (-3250 1750);
FORCEPROP 1 LAST HDL_TAP TRUE
J 2
(-3575 1575);
DISPLAY 0.872340 (-3575 1575);
DISPLAY INVISIBLE (-3575 1575);
FORCEPROP 1 LAST PATH I11
J 2
(-3248 1700);
DISPLAY 0.872340 (-3248 1700);
PAINT GREEN (-3248 1700);
DISPLAY INVISIBLE (-3248 1700);
FORCEADD TAP..1
(-6575 1025);
FORCEPROP 3 LASTPIN (-6625 1025) SIG_NAME P5E_CPU0_P2_TX_BUF_C_DP<13>
J 0
(-6615 1035);
DISPLAY 0.659574 (-6615 1035);
PAINT MONO (-6615 1035);
DISPLAY INVISIBLE (-6615 1035);
FORCEPROP 1 LASTPIN (-6625 1025) BN 13
J 0
(-6637 1033);
DISPLAY 0.680851 (-6637 1033);
PAINT GREEN (-6637 1033);
FORCEPROP 2 LAST CDS_LIB standard
J 0
(-6575 1025);
DISPLAY INVISIBLE (-6575 1025);
FORCEPROP 1 LAST BODY_TYPE PLUMBING
J 0
(-6575 1075);
DISPLAY 0.872340 (-6575 1075);
PAINT GREEN (-6575 1075);
DISPLAY INVISIBLE (-6575 1075);
FORCEPROP 1 LAST HDL_TAP TRUE
J 0
(-6250 900);
DISPLAY 0.872340 (-6250 900);
DISPLAY INVISIBLE (-6250 900);
FORCEPROP 1 LAST PATH I110
J 0
(-6577 1025);
DISPLAY 0.872340 (-6577 1025);
PAINT GREEN (-6577 1025);
DISPLAY INVISIBLE (-6577 1025);
FORCEADD TAP..1
(-6575 1225);
FORCEPROP 3 LASTPIN (-6625 1225) SIG_NAME P5E_CPU0_P2_TX_BUF_C_DP<12>
J 0
(-6615 1235);
DISPLAY 0.659574 (-6615 1235);
PAINT MONO (-6615 1235);
DISPLAY INVISIBLE (-6615 1235);
FORCEPROP 1 LASTPIN (-6625 1225) BN 12
J 0
(-6637 1233);
DISPLAY 0.680851 (-6637 1233);
PAINT GREEN (-6637 1233);
FORCEPROP 2 LAST CDS_LIB standard
J 0
(-6575 1225);
DISPLAY INVISIBLE (-6575 1225);
FORCEPROP 1 LAST BODY_TYPE PLUMBING
J 0
(-6575 1275);
DISPLAY 0.872340 (-6575 1275);
PAINT GREEN (-6575 1275);
DISPLAY INVISIBLE (-6575 1275);
FORCEPROP 1 LAST HDL_TAP TRUE
J 0
(-6250 1100);
DISPLAY 0.872340 (-6250 1100);
DISPLAY INVISIBLE (-6250 1100);
FORCEPROP 1 LAST PATH I111
J 0
(-6577 1225);
DISPLAY 0.872340 (-6577 1225);
PAINT GREEN (-6577 1225);
DISPLAY INVISIBLE (-6577 1225);
FORCEADD TAP..1
(-6375 975);
FORCEPROP 3 LASTPIN (-6425 975) SIG_NAME P5E_CPU0_P2_TX_BUF_C_DN<13>
J 0
(-6415 985);
DISPLAY 0.659574 (-6415 985);
PAINT MONO (-6415 985);
DISPLAY INVISIBLE (-6415 985);
FORCEPROP 1 LASTPIN (-6425 975) BN 13
J 0
(-6437 983);
DISPLAY 0.680851 (-6437 983);
PAINT GREEN (-6437 983);
FORCEPROP 2 LAST CDS_LIB standard
J 0
(-6375 975);
DISPLAY INVISIBLE (-6375 975);
FORCEPROP 1 LAST BODY_TYPE PLUMBING
J 0
(-6375 1025);
DISPLAY 0.872340 (-6375 1025);
PAINT GREEN (-6375 1025);
DISPLAY INVISIBLE (-6375 1025);
FORCEPROP 1 LAST HDL_TAP TRUE
J 0
(-6050 850);
DISPLAY 0.872340 (-6050 850);
DISPLAY INVISIBLE (-6050 850);
FORCEPROP 1 LAST PATH I112
J 0
(-6377 975);
DISPLAY 0.872340 (-6377 975);
PAINT GREEN (-6377 975);
DISPLAY INVISIBLE (-6377 975);
FORCEADD TAP..1
(-6375 1175);
FORCEPROP 3 LASTPIN (-6425 1175) SIG_NAME P5E_CPU0_P2_TX_BUF_C_DN<12>
J 0
(-6415 1185);
DISPLAY 0.659574 (-6415 1185);
PAINT MONO (-6415 1185);
DISPLAY INVISIBLE (-6415 1185);
FORCEPROP 1 LASTPIN (-6425 1175) BN 12
J 0
(-6437 1183);
DISPLAY 0.680851 (-6437 1183);
PAINT GREEN (-6437 1183);
FORCEPROP 2 LAST CDS_LIB standard
J 0
(-6375 1175);
DISPLAY INVISIBLE (-6375 1175);
FORCEPROP 1 LAST BODY_TYPE PLUMBING
J 0
(-6375 1225);
DISPLAY 0.872340 (-6375 1225);
PAINT GREEN (-6375 1225);
DISPLAY INVISIBLE (-6375 1225);
FORCEPROP 1 LAST HDL_TAP TRUE
J 0
(-6050 1050);
DISPLAY 0.872340 (-6050 1050);
DISPLAY INVISIBLE (-6050 1050);
FORCEPROP 1 LAST PATH I113
J 0
(-6377 1175);
DISPLAY 0.872340 (-6377 1175);
PAINT GREEN (-6377 1175);
DISPLAY INVISIBLE (-6377 1175);
FORCEADD TAP..1
(-6375 1375);
FORCEPROP 3 LASTPIN (-6425 1375) SIG_NAME P5E_CPU0_P2_TX_BUF_C_DN<11>
J 0
(-6415 1385);
DISPLAY 0.659574 (-6415 1385);
PAINT MONO (-6415 1385);
DISPLAY INVISIBLE (-6415 1385);
FORCEPROP 1 LASTPIN (-6425 1375) BN 11
J 0
(-6437 1383);
DISPLAY 0.680851 (-6437 1383);
PAINT GREEN (-6437 1383);
FORCEPROP 2 LAST CDS_LIB standard
J 0
(-6375 1375);
DISPLAY INVISIBLE (-6375 1375);
FORCEPROP 1 LAST BODY_TYPE PLUMBING
J 0
(-6375 1425);
DISPLAY 0.872340 (-6375 1425);
PAINT GREEN (-6375 1425);
DISPLAY INVISIBLE (-6375 1425);
FORCEPROP 1 LAST HDL_TAP TRUE
J 0
(-6050 1250);
DISPLAY 0.872340 (-6050 1250);
DISPLAY INVISIBLE (-6050 1250);
FORCEPROP 1 LAST PATH I114
J 0
(-6377 1375);
DISPLAY 0.872340 (-6377 1375);
PAINT GREEN (-6377 1375);
DISPLAY INVISIBLE (-6377 1375);
FORCEADD TAP..1
(-6575 1425);
FORCEPROP 3 LASTPIN (-6625 1425) SIG_NAME P5E_CPU0_P2_TX_BUF_C_DP<11>
J 0
(-6615 1435);
DISPLAY 0.659574 (-6615 1435);
PAINT MONO (-6615 1435);
DISPLAY INVISIBLE (-6615 1435);
FORCEPROP 1 LASTPIN (-6625 1425) BN 11
J 0
(-6637 1433);
DISPLAY 0.680851 (-6637 1433);
PAINT GREEN (-6637 1433);
FORCEPROP 2 LAST CDS_LIB standard
J 0
(-6575 1425);
DISPLAY INVISIBLE (-6575 1425);
FORCEPROP 1 LAST BODY_TYPE PLUMBING
J 0
(-6575 1475);
DISPLAY 0.872340 (-6575 1475);
PAINT GREEN (-6575 1475);
DISPLAY INVISIBLE (-6575 1475);
FORCEPROP 1 LAST HDL_TAP TRUE
J 0
(-6250 1300);
DISPLAY 0.872340 (-6250 1300);
DISPLAY INVISIBLE (-6250 1300);
FORCEPROP 1 LAST PATH I115
J 0
(-6577 1425);
DISPLAY 0.872340 (-6577 1425);
PAINT GREEN (-6577 1425);
DISPLAY INVISIBLE (-6577 1425);
FORCEADD TAP..1
(-6575 1625);
FORCEPROP 3 LASTPIN (-6625 1625) SIG_NAME P5E_CPU0_P2_TX_BUF_C_DP<10>
J 0
(-6615 1635);
DISPLAY 0.659574 (-6615 1635);
PAINT MONO (-6615 1635);
DISPLAY INVISIBLE (-6615 1635);
FORCEPROP 1 LASTPIN (-6625 1625) BN 10
J 0
(-6637 1633);
DISPLAY 0.680851 (-6637 1633);
PAINT GREEN (-6637 1633);
FORCEPROP 2 LAST CDS_LIB standard
J 0
(-6575 1625);
DISPLAY INVISIBLE (-6575 1625);
FORCEPROP 1 LAST BODY_TYPE PLUMBING
J 0
(-6575 1675);
DISPLAY 0.872340 (-6575 1675);
PAINT GREEN (-6575 1675);
DISPLAY INVISIBLE (-6575 1675);
FORCEPROP 1 LAST HDL_TAP TRUE
J 0
(-6250 1500);
DISPLAY 0.872340 (-6250 1500);
DISPLAY INVISIBLE (-6250 1500);
FORCEPROP 1 LAST PATH I116
J 0
(-6577 1625);
DISPLAY 0.872340 (-6577 1625);
PAINT GREEN (-6577 1625);
DISPLAY INVISIBLE (-6577 1625);
FORCEADD TAP..1
(-6575 1825);
FORCEPROP 3 LASTPIN (-6625 1825) SIG_NAME P5E_CPU0_P2_TX_BUF_C_DP<9>
J 0
(-6615 1835);
DISPLAY 0.659574 (-6615 1835);
PAINT MONO (-6615 1835);
DISPLAY INVISIBLE (-6615 1835);
FORCEPROP 1 LASTPIN (-6625 1825) BN 9
J 0
(-6637 1833);
DISPLAY 0.680851 (-6637 1833);
PAINT GREEN (-6637 1833);
FORCEPROP 2 LAST CDS_LIB standard
J 0
(-6575 1825);
DISPLAY INVISIBLE (-6575 1825);
FORCEPROP 1 LAST BODY_TYPE PLUMBING
J 0
(-6575 1875);
DISPLAY 0.872340 (-6575 1875);
PAINT GREEN (-6575 1875);
DISPLAY INVISIBLE (-6575 1875);
FORCEPROP 1 LAST HDL_TAP TRUE
J 0
(-6250 1700);
DISPLAY 0.872340 (-6250 1700);
DISPLAY INVISIBLE (-6250 1700);
FORCEPROP 1 LAST PATH I117
J 0
(-6577 1825);
DISPLAY 0.872340 (-6577 1825);
PAINT GREEN (-6577 1825);
DISPLAY INVISIBLE (-6577 1825);
FORCEADD TAP..1
(-6375 1575);
FORCEPROP 3 LASTPIN (-6425 1575) SIG_NAME P5E_CPU0_P2_TX_BUF_C_DN<10>
J 0
(-6415 1585);
DISPLAY 0.659574 (-6415 1585);
PAINT MONO (-6415 1585);
DISPLAY INVISIBLE (-6415 1585);
FORCEPROP 1 LASTPIN (-6425 1575) BN 10
J 0
(-6437 1583);
DISPLAY 0.680851 (-6437 1583);
PAINT GREEN (-6437 1583);
FORCEPROP 2 LAST CDS_LIB standard
J 0
(-6375 1575);
DISPLAY INVISIBLE (-6375 1575);
FORCEPROP 1 LAST BODY_TYPE PLUMBING
J 0
(-6375 1625);
DISPLAY 0.872340 (-6375 1625);
PAINT GREEN (-6375 1625);
DISPLAY INVISIBLE (-6375 1625);
FORCEPROP 1 LAST HDL_TAP TRUE
J 0
(-6050 1450);
DISPLAY 0.872340 (-6050 1450);
DISPLAY INVISIBLE (-6050 1450);
FORCEPROP 1 LAST PATH I118
J 0
(-6377 1575);
DISPLAY 0.872340 (-6377 1575);
PAINT GREEN (-6377 1575);
DISPLAY INVISIBLE (-6377 1575);
FORCEADD TAP..1
(-6375 1775);
FORCEPROP 3 LASTPIN (-6425 1775) SIG_NAME P5E_CPU0_P2_TX_BUF_C_DN<9>
J 0
(-6415 1785);
DISPLAY 0.659574 (-6415 1785);
PAINT MONO (-6415 1785);
DISPLAY INVISIBLE (-6415 1785);
FORCEPROP 1 LASTPIN (-6425 1775) BN 9
J 0
(-6437 1783);
DISPLAY 0.680851 (-6437 1783);
PAINT GREEN (-6437 1783);
FORCEPROP 2 LAST CDS_LIB standard
J 0
(-6375 1775);
DISPLAY INVISIBLE (-6375 1775);
FORCEPROP 1 LAST BODY_TYPE PLUMBING
J 0
(-6375 1825);
DISPLAY 0.872340 (-6375 1825);
PAINT GREEN (-6375 1825);
DISPLAY INVISIBLE (-6375 1825);
FORCEPROP 1 LAST HDL_TAP TRUE
J 0
(-6050 1650);
DISPLAY 0.872340 (-6050 1650);
DISPLAY INVISIBLE (-6050 1650);
FORCEPROP 1 LAST PATH I119
J 0
(-6377 1775);
DISPLAY 0.872340 (-6377 1775);
PAINT GREEN (-6377 1775);
DISPLAY INVISIBLE (-6377 1775);
FORCEADD TAP..1
R 2
(-3000 950);
FORCEPROP 3 LASTPIN (-2950 950) SIG_NAME P5E_CPU0_P2_TX_BUF_DP<5>
J 0
(-2940 960);
DISPLAY 0.659574 (-2940 960);
PAINT MONO (-2940 960);
DISPLAY INVISIBLE (-2940 960);
FORCEPROP 1 LASTPIN (-2950 950) BN 5
J 2
(-2938 958);
DISPLAY 0.680851 (-2938 958);
PAINT GREEN (-2938 958);
FORCEPROP 2 LAST CDS_LIB standard
J 0
(-3000 950);
DISPLAY INVISIBLE (-3000 950);
FORCEPROP 1 LAST BODY_TYPE PLUMBING
J 2
(-3000 1000);
DISPLAY 0.872340 (-3000 1000);
PAINT GREEN (-3000 1000);
DISPLAY INVISIBLE (-3000 1000);
FORCEPROP 1 LAST HDL_TAP TRUE
J 2
(-3325 825);
DISPLAY 0.872340 (-3325 825);
DISPLAY INVISIBLE (-3325 825);
FORCEPROP 1 LAST PATH I12
J 2
(-2998 950);
DISPLAY 0.872340 (-2998 950);
PAINT GREEN (-2998 950);
DISPLAY INVISIBLE (-2998 950);
FORCEADD TAP..1
(-6575 2025);
FORCEPROP 3 LASTPIN (-6625 2025) SIG_NAME P5E_CPU0_P2_TX_BUF_C_DP<8>
J 0
(-6615 2035);
DISPLAY 0.659574 (-6615 2035);
PAINT MONO (-6615 2035);
DISPLAY INVISIBLE (-6615 2035);
FORCEPROP 1 LASTPIN (-6625 2025) BN 8
J 0
(-6637 2033);
DISPLAY 0.680851 (-6637 2033);
PAINT GREEN (-6637 2033);
FORCEPROP 2 LAST CDS_LIB standard
J 0
(-6575 2025);
DISPLAY INVISIBLE (-6575 2025);
FORCEPROP 1 LAST BODY_TYPE PLUMBING
J 0
(-6575 2075);
DISPLAY 0.872340 (-6575 2075);
PAINT GREEN (-6575 2075);
DISPLAY INVISIBLE (-6575 2075);
FORCEPROP 1 LAST HDL_TAP TRUE
J 0
(-6250 1900);
DISPLAY 0.872340 (-6250 1900);
DISPLAY INVISIBLE (-6250 1900);
FORCEPROP 1 LAST PATH I120
J 0
(-6577 2025);
DISPLAY 0.872340 (-6577 2025);
PAINT GREEN (-6577 2025);
DISPLAY INVISIBLE (-6577 2025);
FORCEADD TAP..1
(-6375 1975);
FORCEPROP 3 LASTPIN (-6425 1975) SIG_NAME P5E_CPU0_P2_TX_BUF_C_DN<8>
J 0
(-6415 1985);
DISPLAY 0.659574 (-6415 1985);
PAINT MONO (-6415 1985);
DISPLAY INVISIBLE (-6415 1985);
FORCEPROP 1 LASTPIN (-6425 1975) BN 8
J 0
(-6437 1983);
DISPLAY 0.680851 (-6437 1983);
PAINT GREEN (-6437 1983);
FORCEPROP 2 LAST CDS_LIB standard
J 0
(-6375 1975);
DISPLAY INVISIBLE (-6375 1975);
FORCEPROP 1 LAST BODY_TYPE PLUMBING
J 0
(-6375 2025);
DISPLAY 0.872340 (-6375 2025);
PAINT GREEN (-6375 2025);
DISPLAY INVISIBLE (-6375 2025);
FORCEPROP 1 LAST HDL_TAP TRUE
J 0
(-6050 1850);
DISPLAY 0.872340 (-6050 1850);
DISPLAY INVISIBLE (-6050 1850);
FORCEPROP 1 LAST PATH I121
J 0
(-6377 1975);
DISPLAY 0.872340 (-6377 1975);
PAINT GREEN (-6377 1975);
DISPLAY INVISIBLE (-6377 1975);
FORCEADD TAP..1
(-1925 3150);
FORCEPROP 3 LASTPIN (-1975 3150) SIG_NAME P5E_CPU0_P2_TX_BUF_DP<0>
J 0
(-1965 3160);
DISPLAY 0.659574 (-1965 3160);
PAINT MONO (-1965 3160);
DISPLAY INVISIBLE (-1965 3160);
FORCEPROP 1 LASTPIN (-1975 3150) BN 0
J 0
(-1987 3158);
DISPLAY 0.680851 (-1987 3158);
PAINT GREEN (-1987 3158);
FORCEPROP 2 LAST CDS_LIB standard
J 0
(-1925 3150);
DISPLAY INVISIBLE (-1925 3150);
FORCEPROP 1 LAST BODY_TYPE PLUMBING
J 0
(-1925 3200);
DISPLAY 0.872340 (-1925 3200);
PAINT GREEN (-1925 3200);
DISPLAY INVISIBLE (-1925 3200);
FORCEPROP 1 LAST HDL_TAP TRUE
J 0
(-1600 3025);
DISPLAY 0.872340 (-1600 3025);
DISPLAY INVISIBLE (-1600 3025);
FORCEPROP 1 LAST PATH I122
J 0
(-1927 3150);
DISPLAY 0.872340 (-1927 3150);
PAINT GREEN (-1927 3150);
DISPLAY INVISIBLE (-1927 3150);
FORCEADD TAP..1
(-1725 3050);
FORCEPROP 3 LASTPIN (-1775 3050) SIG_NAME P5E_CPU0_P2_TX_BUF_DN<0>
J 0
(-1765 3060);
DISPLAY 0.659574 (-1765 3060);
PAINT MONO (-1765 3060);
DISPLAY INVISIBLE (-1765 3060);
FORCEPROP 1 LASTPIN (-1775 3050) BN 0
J 0
(-1787 3058);
DISPLAY 0.680851 (-1787 3058);
PAINT GREEN (-1787 3058);
FORCEPROP 2 LAST CDS_LIB standard
J 0
(-1725 3050);
DISPLAY INVISIBLE (-1725 3050);
FORCEPROP 1 LAST BODY_TYPE PLUMBING
J 0
(-1725 3100);
DISPLAY 0.872340 (-1725 3100);
PAINT GREEN (-1725 3100);
DISPLAY INVISIBLE (-1725 3100);
FORCEPROP 1 LAST HDL_TAP TRUE
J 0
(-1400 2925);
DISPLAY 0.872340 (-1400 2925);
DISPLAY INVISIBLE (-1400 2925);
FORCEPROP 1 LAST PATH I123
J 0
(-1727 3050);
DISPLAY 0.872340 (-1727 3050);
PAINT GREEN (-1727 3050);
DISPLAY INVISIBLE (-1727 3050);
FORCEADD TAP..1
(-1925 3500);
FORCEPROP 3 LASTPIN (-1975 3500) SIG_NAME P5E_CPU0_P2_TX_BUF_DP<1>
J 0
(-1965 3510);
DISPLAY 0.659574 (-1965 3510);
PAINT MONO (-1965 3510);
DISPLAY INVISIBLE (-1965 3510);
FORCEPROP 1 LASTPIN (-1975 3500) BN 1
J 0
(-1987 3508);
DISPLAY 0.680851 (-1987 3508);
PAINT GREEN (-1987 3508);
FORCEPROP 2 LAST CDS_LIB standard
J 0
(-1925 3500);
DISPLAY INVISIBLE (-1925 3500);
FORCEPROP 1 LAST BODY_TYPE PLUMBING
J 0
(-1925 3550);
DISPLAY 0.872340 (-1925 3550);
PAINT GREEN (-1925 3550);
DISPLAY INVISIBLE (-1925 3550);
FORCEPROP 1 LAST HDL_TAP TRUE
J 0
(-1600 3375);
DISPLAY 0.872340 (-1600 3375);
DISPLAY INVISIBLE (-1600 3375);
FORCEPROP 1 LAST PATH I124
J 0
(-1927 3500);
DISPLAY 0.872340 (-1927 3500);
PAINT GREEN (-1927 3500);
DISPLAY INVISIBLE (-1927 3500);
FORCEADD TAP..1
(-1925 3850);
FORCEPROP 3 LASTPIN (-1975 3850) SIG_NAME P5E_CPU0_P2_TX_BUF_DP<2>
J 0
(-1965 3860);
DISPLAY 0.659574 (-1965 3860);
PAINT MONO (-1965 3860);
DISPLAY INVISIBLE (-1965 3860);
FORCEPROP 1 LASTPIN (-1975 3850) BN 2
J 0
(-1987 3858);
DISPLAY 0.680851 (-1987 3858);
PAINT GREEN (-1987 3858);
FORCEPROP 2 LAST CDS_LIB standard
J 0
(-1925 3850);
DISPLAY INVISIBLE (-1925 3850);
FORCEPROP 1 LAST BODY_TYPE PLUMBING
J 0
(-1925 3900);
DISPLAY 0.872340 (-1925 3900);
PAINT GREEN (-1925 3900);
DISPLAY INVISIBLE (-1925 3900);
FORCEPROP 1 LAST HDL_TAP TRUE
J 0
(-1600 3725);
DISPLAY 0.872340 (-1600 3725);
DISPLAY INVISIBLE (-1600 3725);
FORCEPROP 1 LAST PATH I125
J 0
(-1927 3850);
DISPLAY 0.872340 (-1927 3850);
PAINT GREEN (-1927 3850);
DISPLAY INVISIBLE (-1927 3850);
FORCEADD TAP..1
(-1725 3400);
FORCEPROP 3 LASTPIN (-1775 3400) SIG_NAME P5E_CPU0_P2_TX_BUF_DN<1>
J 0
(-1765 3410);
DISPLAY 0.659574 (-1765 3410);
PAINT MONO (-1765 3410);
DISPLAY INVISIBLE (-1765 3410);
FORCEPROP 1 LASTPIN (-1775 3400) BN 1
J 0
(-1787 3408);
DISPLAY 0.680851 (-1787 3408);
PAINT GREEN (-1787 3408);
FORCEPROP 2 LAST CDS_LIB standard
J 0
(-1725 3400);
DISPLAY INVISIBLE (-1725 3400);
FORCEPROP 1 LAST BODY_TYPE PLUMBING
J 0
(-1725 3450);
DISPLAY 0.872340 (-1725 3450);
PAINT GREEN (-1725 3450);
DISPLAY INVISIBLE (-1725 3450);
FORCEPROP 1 LAST HDL_TAP TRUE
J 0
(-1400 3275);
DISPLAY 0.872340 (-1400 3275);
DISPLAY INVISIBLE (-1400 3275);
FORCEPROP 1 LAST PATH I126
J 0
(-1727 3400);
DISPLAY 0.872340 (-1727 3400);
PAINT GREEN (-1727 3400);
DISPLAY INVISIBLE (-1727 3400);
FORCEADD TAP..1
(-1725 3750);
FORCEPROP 3 LASTPIN (-1775 3750) SIG_NAME P5E_CPU0_P2_TX_BUF_DN<2>
J 0
(-1765 3760);
DISPLAY 0.659574 (-1765 3760);
PAINT MONO (-1765 3760);
DISPLAY INVISIBLE (-1765 3760);
FORCEPROP 1 LASTPIN (-1775 3750) BN 2
J 0
(-1787 3758);
DISPLAY 0.680851 (-1787 3758);
PAINT GREEN (-1787 3758);
FORCEPROP 2 LAST CDS_LIB standard
J 0
(-1725 3750);
DISPLAY INVISIBLE (-1725 3750);
FORCEPROP 1 LAST BODY_TYPE PLUMBING
J 0
(-1725 3800);
DISPLAY 0.872340 (-1725 3800);
PAINT GREEN (-1725 3800);
DISPLAY INVISIBLE (-1725 3800);
FORCEPROP 1 LAST HDL_TAP TRUE
J 0
(-1400 3625);
DISPLAY 0.872340 (-1400 3625);
DISPLAY INVISIBLE (-1400 3625);
FORCEPROP 1 LAST PATH I127
J 0
(-1727 3750);
DISPLAY 0.872340 (-1727 3750);
PAINT GREEN (-1727 3750);
DISPLAY INVISIBLE (-1727 3750);
FORCEADD OFFPAGE..2
(-5375 2050);
FORCEPROP 2 LAST $XR0 115 
J 0
(-5186 2050);
DISPLAY 0.638298 (-5186 2050);
PAINT MONO (-5186 2050);
FORCEPROP 2 LAST CDS_LIB standard
J 0
(-5375 2050);
DISPLAY INVISIBLE (-5375 2050);
FORCEPROP 1 LAST OFFPAGE TRUE
J 0
(-5050 1925);
DISPLAY 0.872340 (-5050 1925);
DISPLAY INVISIBLE (-5050 1925);
FORCEPROP 1 LAST COMMENT_BODY TRUE
J 0
(-5420 1955);
DISPLAY 0.872340 (-5420 1955);
PAINT GREEN (-5420 1955);
DISPLAY INVISIBLE (-5420 1955);
FORCEPROP 2 LAST PATH I128
J 0
(-5175 2100);
DISPLAY 0.680851 (-5175 2100);
DISPLAY INVISIBLE (-5175 2100);
FORCEADD OFFPAGE..2
(-5375 2000);
FORCEPROP 2 LAST $XR0 115 
J 0
(-5186 2000);
DISPLAY 0.638298 (-5186 2000);
PAINT MONO (-5186 2000);
FORCEPROP 2 LAST CDS_LIB standard
J 0
(-5375 2000);
DISPLAY INVISIBLE (-5375 2000);
FORCEPROP 1 LAST OFFPAGE TRUE
J 0
(-5050 1875);
DISPLAY 0.872340 (-5050 1875);
DISPLAY INVISIBLE (-5050 1875);
FORCEPROP 1 LAST COMMENT_BODY TRUE
J 0
(-5420 1905);
DISPLAY 0.872340 (-5420 1905);
PAINT GREEN (-5420 1905);
DISPLAY INVISIBLE (-5420 1905);
FORCEPROP 2 LAST PATH I129
J 0
(-5175 2050);
DISPLAY 0.680851 (-5175 2050);
DISPLAY INVISIBLE (-5175 2050);
FORCEADD TAP..1
R 2
(-3000 1150);
FORCEPROP 3 LASTPIN (-2950 1150) SIG_NAME P5E_CPU0_P2_TX_BUF_DP<4>
J 0
(-2940 1160);
DISPLAY 0.659574 (-2940 1160);
PAINT MONO (-2940 1160);
DISPLAY INVISIBLE (-2940 1160);
FORCEPROP 1 LASTPIN (-2950 1150) BN 4
J 2
(-2938 1158);
DISPLAY 0.680851 (-2938 1158);
PAINT GREEN (-2938 1158);
FORCEPROP 2 LAST CDS_LIB standard
J 0
(-3000 1150);
DISPLAY INVISIBLE (-3000 1150);
FORCEPROP 1 LAST BODY_TYPE PLUMBING
J 2
(-3000 1200);
DISPLAY 0.872340 (-3000 1200);
PAINT GREEN (-3000 1200);
DISPLAY INVISIBLE (-3000 1200);
FORCEPROP 1 LAST HDL_TAP TRUE
J 2
(-3325 1025);
DISPLAY 0.872340 (-3325 1025);
DISPLAY INVISIBLE (-3325 1025);
FORCEPROP 1 LAST PATH I13
J 2
(-2998 1150);
DISPLAY 0.872340 (-2998 1150);
PAINT GREEN (-2998 1150);
DISPLAY INVISIBLE (-2998 1150);
FORCEADD TAP..1
(-1925 4200);
FORCEPROP 3 LASTPIN (-1975 4200) SIG_NAME P5E_CPU0_P2_TX_BUF_DP<3>
J 0
(-1965 4210);
DISPLAY 0.659574 (-1965 4210);
PAINT MONO (-1965 4210);
DISPLAY INVISIBLE (-1965 4210);
FORCEPROP 1 LASTPIN (-1975 4200) BN 3
J 0
(-1987 4208);
DISPLAY 0.680851 (-1987 4208);
PAINT GREEN (-1987 4208);
FORCEPROP 2 LAST CDS_LIB standard
J 0
(-1925 4200);
DISPLAY INVISIBLE (-1925 4200);
FORCEPROP 1 LAST BODY_TYPE PLUMBING
J 0
(-1925 4250);
DISPLAY 0.872340 (-1925 4250);
PAINT GREEN (-1925 4250);
DISPLAY INVISIBLE (-1925 4250);
FORCEPROP 1 LAST HDL_TAP TRUE
J 0
(-1600 4075);
DISPLAY 0.872340 (-1600 4075);
DISPLAY INVISIBLE (-1600 4075);
FORCEPROP 1 LAST PATH I130
J 0
(-1927 4200);
DISPLAY 0.872340 (-1927 4200);
PAINT GREEN (-1927 4200);
DISPLAY INVISIBLE (-1927 4200);
FORCEADD TAP..1
(-1725 4100);
FORCEPROP 3 LASTPIN (-1775 4100) SIG_NAME P5E_CPU0_P2_TX_BUF_DN<3>
J 0
(-1765 4110);
DISPLAY 0.659574 (-1765 4110);
PAINT MONO (-1765 4110);
DISPLAY INVISIBLE (-1765 4110);
FORCEPROP 1 LASTPIN (-1775 4100) BN 3
J 0
(-1787 4108);
DISPLAY 0.680851 (-1787 4108);
PAINT GREEN (-1787 4108);
FORCEPROP 2 LAST CDS_LIB standard
J 0
(-1725 4100);
DISPLAY INVISIBLE (-1725 4100);
FORCEPROP 1 LAST BODY_TYPE PLUMBING
J 0
(-1725 4150);
DISPLAY 0.872340 (-1725 4150);
PAINT GREEN (-1725 4150);
DISPLAY INVISIBLE (-1725 4150);
FORCEPROP 1 LAST HDL_TAP TRUE
J 0
(-1400 3975);
DISPLAY 0.872340 (-1400 3975);
DISPLAY INVISIBLE (-1400 3975);
FORCEPROP 1 LAST PATH I131
J 0
(-1727 4100);
DISPLAY 0.872340 (-1727 4100);
PAINT GREEN (-1727 4100);
DISPLAY INVISIBLE (-1727 4100);
FORCEADD TAP..1
(-1925 4550);
FORCEPROP 3 LASTPIN (-1975 4550) SIG_NAME P5E_CPU0_P2_TX_BUF_DP<4>
J 0
(-1965 4560);
DISPLAY 0.659574 (-1965 4560);
PAINT MONO (-1965 4560);
DISPLAY INVISIBLE (-1965 4560);
FORCEPROP 1 LASTPIN (-1975 4550) BN 4
J 0
(-1987 4558);
DISPLAY 0.680851 (-1987 4558);
PAINT GREEN (-1987 4558);
FORCEPROP 2 LAST CDS_LIB standard
J 0
(-1925 4550);
DISPLAY INVISIBLE (-1925 4550);
FORCEPROP 1 LAST BODY_TYPE PLUMBING
J 0
(-1925 4600);
DISPLAY 0.872340 (-1925 4600);
PAINT GREEN (-1925 4600);
DISPLAY INVISIBLE (-1925 4600);
FORCEPROP 1 LAST HDL_TAP TRUE
J 0
(-1600 4425);
DISPLAY 0.872340 (-1600 4425);
DISPLAY INVISIBLE (-1600 4425);
FORCEPROP 1 LAST PATH I132
J 0
(-1927 4550);
DISPLAY 0.872340 (-1927 4550);
PAINT GREEN (-1927 4550);
DISPLAY INVISIBLE (-1927 4550);
FORCEADD TAP..1
(-1925 4900);
FORCEPROP 3 LASTPIN (-1975 4900) SIG_NAME P5E_CPU0_P2_TX_BUF_DP<5>
J 0
(-1965 4910);
DISPLAY 0.659574 (-1965 4910);
PAINT MONO (-1965 4910);
DISPLAY INVISIBLE (-1965 4910);
FORCEPROP 1 LASTPIN (-1975 4900) BN 5
J 0
(-1987 4908);
DISPLAY 0.680851 (-1987 4908);
PAINT GREEN (-1987 4908);
FORCEPROP 2 LAST CDS_LIB standard
J 0
(-1925 4900);
DISPLAY INVISIBLE (-1925 4900);
FORCEPROP 1 LAST BODY_TYPE PLUMBING
J 0
(-1925 4950);
DISPLAY 0.872340 (-1925 4950);
PAINT GREEN (-1925 4950);
DISPLAY INVISIBLE (-1925 4950);
FORCEPROP 1 LAST HDL_TAP TRUE
J 0
(-1600 4775);
DISPLAY 0.872340 (-1600 4775);
DISPLAY INVISIBLE (-1600 4775);
FORCEPROP 1 LAST PATH I133
J 0
(-1927 4900);
DISPLAY 0.872340 (-1927 4900);
PAINT GREEN (-1927 4900);
DISPLAY INVISIBLE (-1927 4900);
FORCEADD TAP..1
(-1725 4450);
FORCEPROP 3 LASTPIN (-1775 4450) SIG_NAME P5E_CPU0_P2_TX_BUF_DN<4>
J 0
(-1765 4460);
DISPLAY 0.659574 (-1765 4460);
PAINT MONO (-1765 4460);
DISPLAY INVISIBLE (-1765 4460);
FORCEPROP 1 LASTPIN (-1775 4450) BN 4
J 0
(-1787 4458);
DISPLAY 0.680851 (-1787 4458);
PAINT GREEN (-1787 4458);
FORCEPROP 2 LAST CDS_LIB standard
J 0
(-1725 4450);
DISPLAY INVISIBLE (-1725 4450);
FORCEPROP 1 LAST BODY_TYPE PLUMBING
J 0
(-1725 4500);
DISPLAY 0.872340 (-1725 4500);
PAINT GREEN (-1725 4500);
DISPLAY INVISIBLE (-1725 4500);
FORCEPROP 1 LAST HDL_TAP TRUE
J 0
(-1400 4325);
DISPLAY 0.872340 (-1400 4325);
DISPLAY INVISIBLE (-1400 4325);
FORCEPROP 1 LAST PATH I134
J 0
(-1727 4450);
DISPLAY 0.872340 (-1727 4450);
PAINT GREEN (-1727 4450);
DISPLAY INVISIBLE (-1727 4450);
FORCEADD TAP..1
(-1725 4800);
FORCEPROP 3 LASTPIN (-1775 4800) SIG_NAME P5E_CPU0_P2_TX_BUF_DN<5>
J 0
(-1765 4810);
DISPLAY 0.659574 (-1765 4810);
PAINT MONO (-1765 4810);
DISPLAY INVISIBLE (-1765 4810);
FORCEPROP 1 LASTPIN (-1775 4800) BN 5
J 0
(-1787 4808);
DISPLAY 0.680851 (-1787 4808);
PAINT GREEN (-1787 4808);
FORCEPROP 2 LAST CDS_LIB standard
J 0
(-1725 4800);
DISPLAY INVISIBLE (-1725 4800);
FORCEPROP 1 LAST BODY_TYPE PLUMBING
J 0
(-1725 4850);
DISPLAY 0.872340 (-1725 4850);
PAINT GREEN (-1725 4850);
DISPLAY INVISIBLE (-1725 4850);
FORCEPROP 1 LAST HDL_TAP TRUE
J 0
(-1400 4675);
DISPLAY 0.872340 (-1400 4675);
DISPLAY INVISIBLE (-1400 4675);
FORCEPROP 1 LAST PATH I135
J 0
(-1727 4800);
DISPLAY 0.872340 (-1727 4800);
PAINT GREEN (-1727 4800);
DISPLAY INVISIBLE (-1727 4800);
FORCEADD TAP..1
(-1925 5250);
FORCEPROP 3 LASTPIN (-1975 5250) SIG_NAME P5E_CPU0_P2_TX_BUF_DP<6>
J 0
(-1965 5260);
DISPLAY 0.659574 (-1965 5260);
PAINT MONO (-1965 5260);
DISPLAY INVISIBLE (-1965 5260);
FORCEPROP 1 LASTPIN (-1975 5250) BN 6
J 0
(-1987 5258);
DISPLAY 0.680851 (-1987 5258);
PAINT GREEN (-1987 5258);
FORCEPROP 2 LAST CDS_LIB standard
J 0
(-1925 5250);
DISPLAY INVISIBLE (-1925 5250);
FORCEPROP 1 LAST BODY_TYPE PLUMBING
J 0
(-1925 5300);
DISPLAY 0.872340 (-1925 5300);
PAINT GREEN (-1925 5300);
DISPLAY INVISIBLE (-1925 5300);
FORCEPROP 1 LAST HDL_TAP TRUE
J 0
(-1600 5125);
DISPLAY 0.872340 (-1600 5125);
DISPLAY INVISIBLE (-1600 5125);
FORCEPROP 1 LAST PATH I136
J 0
(-1927 5250);
DISPLAY 0.872340 (-1927 5250);
PAINT GREEN (-1927 5250);
DISPLAY INVISIBLE (-1927 5250);
FORCEADD TAP..1
(-1725 5150);
FORCEPROP 3 LASTPIN (-1775 5150) SIG_NAME P5E_CPU0_P2_TX_BUF_DN<6>
J 0
(-1765 5160);
DISPLAY 0.659574 (-1765 5160);
PAINT MONO (-1765 5160);
DISPLAY INVISIBLE (-1765 5160);
FORCEPROP 1 LASTPIN (-1775 5150) BN 6
J 0
(-1787 5158);
DISPLAY 0.680851 (-1787 5158);
PAINT GREEN (-1787 5158);
FORCEPROP 2 LAST CDS_LIB standard
J 0
(-1725 5150);
DISPLAY INVISIBLE (-1725 5150);
FORCEPROP 1 LAST BODY_TYPE PLUMBING
J 0
(-1725 5200);
DISPLAY 0.872340 (-1725 5200);
PAINT GREEN (-1725 5200);
DISPLAY INVISIBLE (-1725 5200);
FORCEPROP 1 LAST HDL_TAP TRUE
J 0
(-1400 5025);
DISPLAY 0.872340 (-1400 5025);
DISPLAY INVISIBLE (-1400 5025);
FORCEPROP 1 LAST PATH I137
J 0
(-1727 5150);
DISPLAY 0.872340 (-1727 5150);
PAINT GREEN (-1727 5150);
DISPLAY INVISIBLE (-1727 5150);
FORCEADD TAP..1
(-1925 5600);
FORCEPROP 3 LASTPIN (-1975 5600) SIG_NAME P5E_CPU0_P2_TX_BUF_DP<7>
J 0
(-1965 5610);
DISPLAY 0.659574 (-1965 5610);
PAINT MONO (-1965 5610);
DISPLAY INVISIBLE (-1965 5610);
FORCEPROP 1 LASTPIN (-1975 5600) BN 7
J 0
(-1987 5608);
DISPLAY 0.680851 (-1987 5608);
PAINT GREEN (-1987 5608);
FORCEPROP 2 LAST CDS_LIB standard
J 0
(-1925 5600);
DISPLAY INVISIBLE (-1925 5600);
FORCEPROP 1 LAST BODY_TYPE PLUMBING
J 0
(-1925 5650);
DISPLAY 0.872340 (-1925 5650);
PAINT GREEN (-1925 5650);
DISPLAY INVISIBLE (-1925 5650);
FORCEPROP 1 LAST HDL_TAP TRUE
J 0
(-1600 5475);
DISPLAY 0.872340 (-1600 5475);
DISPLAY INVISIBLE (-1600 5475);
FORCEPROP 1 LAST PATH I138
J 0
(-1927 5600);
DISPLAY 0.872340 (-1927 5600);
PAINT GREEN (-1927 5600);
DISPLAY INVISIBLE (-1927 5600);
FORCEADD TAP..1
(-1725 5500);
FORCEPROP 3 LASTPIN (-1775 5500) SIG_NAME P5E_CPU0_P2_TX_BUF_DN<7>
J 0
(-1765 5510);
DISPLAY 0.659574 (-1765 5510);
PAINT MONO (-1765 5510);
DISPLAY INVISIBLE (-1765 5510);
FORCEPROP 1 LASTPIN (-1775 5500) BN 7
J 0
(-1787 5508);
DISPLAY 0.680851 (-1787 5508);
PAINT GREEN (-1787 5508);
FORCEPROP 2 LAST CDS_LIB standard
J 0
(-1725 5500);
DISPLAY INVISIBLE (-1725 5500);
FORCEPROP 1 LAST BODY_TYPE PLUMBING
J 0
(-1725 5550);
DISPLAY 0.872340 (-1725 5550);
PAINT GREEN (-1725 5550);
DISPLAY INVISIBLE (-1725 5550);
FORCEPROP 1 LAST HDL_TAP TRUE
J 0
(-1400 5375);
DISPLAY 0.872340 (-1400 5375);
DISPLAY INVISIBLE (-1400 5375);
FORCEPROP 1 LAST PATH I139
J 0
(-1727 5500);
DISPLAY 0.872340 (-1727 5500);
PAINT GREEN (-1727 5500);
DISPLAY INVISIBLE (-1727 5500);
FORCEADD TAP..1
R 2
(-3000 1350);
FORCEPROP 3 LASTPIN (-2950 1350) SIG_NAME P5E_CPU0_P2_TX_BUF_DP<3>
J 0
(-2940 1360);
DISPLAY 0.659574 (-2940 1360);
PAINT MONO (-2940 1360);
DISPLAY INVISIBLE (-2940 1360);
FORCEPROP 1 LASTPIN (-2950 1350) BN 3
J 2
(-2938 1358);
DISPLAY 0.680851 (-2938 1358);
PAINT GREEN (-2938 1358);
FORCEPROP 2 LAST CDS_LIB standard
J 0
(-3000 1350);
DISPLAY INVISIBLE (-3000 1350);
FORCEPROP 1 LAST BODY_TYPE PLUMBING
J 2
(-3000 1400);
DISPLAY 0.872340 (-3000 1400);
PAINT GREEN (-3000 1400);
DISPLAY INVISIBLE (-3000 1400);
FORCEPROP 1 LAST HDL_TAP TRUE
J 2
(-3325 1225);
DISPLAY 0.872340 (-3325 1225);
DISPLAY INVISIBLE (-3325 1225);
FORCEPROP 1 LAST PATH I14
J 2
(-2998 1350);
DISPLAY 0.872340 (-2998 1350);
PAINT GREEN (-2998 1350);
DISPLAY INVISIBLE (-2998 1350);
FORCEADD OFFPAGE..5
R 2
(-750 5525);
FORCEPROP 2 LAST $XR0 298 
J 0
(-561 5525);
DISPLAY 0.638298 (-561 5525);
PAINT MONO (-561 5525);
FORCEPROP 2 LAST CDS_LIB standard
J 0
(-750 5525);
DISPLAY INVISIBLE (-750 5525);
FORCEPROP 1 LAST OFFPAGE TRUE
J 2
(-1075 5400);
DISPLAY 0.872340 (-1075 5400);
PAINT GREEN (-1075 5400);
DISPLAY INVISIBLE (-1075 5400);
FORCEPROP 1 LAST COMMENT_BODY TRUE
J 2
(-850 5450);
DISPLAY 0.872340 (-850 5450);
PAINT GREEN (-850 5450);
DISPLAY INVISIBLE (-850 5450);
FORCEPROP 2 LAST PATH I140
J 0
(-575 5600);
DISPLAY 0.680851 (-575 5600);
DISPLAY INVISIBLE (-575 5600);
FORCEADD OFFPAGE..5
R 2
(-725 5625);
FORCEPROP 2 LAST $XR0 298 
J 0
(-536 5625);
DISPLAY 0.638298 (-536 5625);
PAINT MONO (-536 5625);
FORCEPROP 2 LAST CDS_LIB standard
J 0
(-725 5625);
DISPLAY INVISIBLE (-725 5625);
FORCEPROP 1 LAST OFFPAGE TRUE
J 2
(-1050 5500);
DISPLAY 0.872340 (-1050 5500);
PAINT GREEN (-1050 5500);
DISPLAY INVISIBLE (-1050 5500);
FORCEPROP 1 LAST COMMENT_BODY TRUE
J 2
(-825 5550);
DISPLAY 0.872340 (-825 5550);
PAINT GREEN (-825 5550);
DISPLAY INVISIBLE (-825 5550);
FORCEPROP 2 LAST PATH I141
J 0
(-550 5700);
DISPLAY 0.680851 (-550 5700);
DISPLAY INVISIBLE (-550 5700);
FORCEADD PT5161LRS..11
(-2650 4350);
FORCEPROP 1 LAST LOCATION U6012
J 0
(-3000 5975);
DISPLAY 0.723404 (-3000 5975);
PAINT GREEN (-3000 5975);
FORCEPROP 0 LAST $SEC 11
J 0
(-3000 6125);
DISPLAY 0.680851 (-3000 6125);
PAINT MONO (-3000 6125);
DISPLAY INVISIBLE (-3000 6125);
FORCEPROP 0 LAST CDS_SEC 11
J 0
(-3000 6125);
DISPLAY 0.680851 (-3000 6125);
DISPLAY INVISIBLE (-3000 6125);
FORCEPROP 0 LASTPIN (-2200 5500) $PN CK10
J 0
(-2190 5510);
DISPLAY 0.680851 (-2190 5510);
PAINT MONO (-2190 5510);
FORCEPROP 0 LASTPIN (-2200 5150) $PN CU10
J 0
(-2190 5160);
DISPLAY 0.680851 (-2190 5160);
PAINT MONO (-2190 5160);
FORCEPROP 0 LASTPIN (-2200 4800) $PN DD10
J 0
(-2190 4810);
DISPLAY 0.680851 (-2190 4810);
PAINT MONO (-2190 4810);
FORCEPROP 0 LASTPIN (-2200 4450) $PN DL10
J 0
(-2190 4460);
DISPLAY 0.680851 (-2190 4460);
PAINT MONO (-2190 4460);
FORCEPROP 0 LASTPIN (-2200 4100) $PN DV10
J 0
(-2190 4110);
DISPLAY 0.680851 (-2190 4110);
PAINT MONO (-2190 4110);
FORCEPROP 0 LASTPIN (-2200 3750) $PN EE10
J 0
(-2190 3760);
DISPLAY 0.680851 (-2190 3760);
PAINT MONO (-2190 3760);
FORCEPROP 0 LASTPIN (-2200 3400) $PN EM10
J 0
(-2190 3410);
DISPLAY 0.680851 (-2190 3410);
PAINT MONO (-2190 3410);
FORCEPROP 0 LASTPIN (-2200 3050) $PN EW10
J 0
(-2190 3060);
DISPLAY 0.680851 (-2190 3060);
PAINT MONO (-2190 3060);
FORCEPROP 0 LASTPIN (-2200 5600) $PN CH7
J 0
(-2190 5610);
DISPLAY 0.680851 (-2190 5610);
PAINT MONO (-2190 5610);
FORCEPROP 0 LASTPIN (-2200 5250) $PN CR7
J 0
(-2190 5260);
DISPLAY 0.680851 (-2190 5260);
PAINT MONO (-2190 5260);
FORCEPROP 0 LASTPIN (-2200 4900) $PN DB7
J 0
(-2190 4910);
DISPLAY 0.680851 (-2190 4910);
PAINT MONO (-2190 4910);
FORCEPROP 0 LASTPIN (-2200 4550) $PN DJ7
J 0
(-2190 4560);
DISPLAY 0.680851 (-2190 4560);
PAINT MONO (-2190 4560);
FORCEPROP 0 LASTPIN (-2200 4200) $PN DT7
J 0
(-2190 4210);
DISPLAY 0.680851 (-2190 4210);
PAINT MONO (-2190 4210);
FORCEPROP 0 LASTPIN (-2200 3850) $PN EC7
J 0
(-2190 3860);
DISPLAY 0.680851 (-2190 3860);
PAINT MONO (-2190 3860);
FORCEPROP 0 LASTPIN (-2200 3500) $PN EK7
J 0
(-2190 3510);
DISPLAY 0.680851 (-2190 3510);
PAINT MONO (-2190 3510);
FORCEPROP 0 LASTPIN (-2200 3150) $PN EU7
J 0
(-2190 3160);
DISPLAY 0.680851 (-2190 3160);
PAINT MONO (-2190 3160);
FORCEPROP 2 LAST VALUE PT5161LRS
J 0
(-3000 6025);
DISPLAY 0.680851 (-3000 6025);
FORCEPROP 1 LAST MATERIAL IC
J 0
(-3000 5825);
DISPLAY 0.723404 (-3000 5825);
PAINT GREEN (-3000 5825);
FORCEPROP 2 LAST PART_TYPE SMLF
J 0
(-3000 6075);
DISPLAY 0.680851 (-3000 6075);
FORCEPROP 2 LAST CDS_LIB pure_quanta
J 0
(-2650 4350);
DISPLAY INVISIBLE (-2650 4350);
FORCEPROP 1 LAST CDS_LMAN_SYM_OUTLINE -350,1450,300,-1400
J 0
(-2650 4350);
DISPLAY 0.468085 (-2650 4350);
PAINT GREEN (-2650 4350);
DISPLAY INVISIBLE (-2650 4350);
FORCEPROP 1 LAST NEEDS_NO_SIZE TRUE
J 0
(-2650 4350);
DISPLAY 0.723404 (-2650 4350);
PAINT GREEN (-2650 4350);
DISPLAY INVISIBLE (-2650 4350);
FORCEPROP 1 LAST PATH I142
J 0
(-2650 4350);
DISPLAY 0.723404 (-2650 4350);
PAINT GREEN (-2650 4350);
DISPLAY INVISIBLE (-2650 4350);
FORCEPROP 1 LAST PART_NUMBER AJ051610U03
J 0
(-3000 5900);
DISPLAY 0.723404 (-3000 5900);
PAINT GREEN (-3000 5900);
DISPLAY INVISIBLE (-3000 5900);
FORCEADD TAP..1
R 2
(-3000 1750);
FORCEPROP 3 LASTPIN (-2950 1750) SIG_NAME P5E_CPU0_P2_TX_BUF_DP<1>
J 0
(-2940 1760);
DISPLAY 0.659574 (-2940 1760);
PAINT MONO (-2940 1760);
DISPLAY INVISIBLE (-2940 1760);
FORCEPROP 1 LASTPIN (-2950 1750) BN 1
J 2
(-2938 1758);
DISPLAY 0.680851 (-2938 1758);
PAINT GREEN (-2938 1758);
FORCEPROP 2 LAST CDS_LIB standard
J 0
(-3000 1750);
DISPLAY INVISIBLE (-3000 1750);
FORCEPROP 1 LAST BODY_TYPE PLUMBING
J 2
(-3000 1800);
DISPLAY 0.872340 (-3000 1800);
PAINT GREEN (-3000 1800);
DISPLAY INVISIBLE (-3000 1800);
FORCEPROP 1 LAST HDL_TAP TRUE
J 2
(-3325 1625);
DISPLAY 0.872340 (-3325 1625);
DISPLAY INVISIBLE (-3325 1625);
FORCEPROP 1 LAST PATH I15
J 2
(-2998 1750);
DISPLAY 0.872340 (-2998 1750);
PAINT GREEN (-2998 1750);
DISPLAY INVISIBLE (-2998 1750);
FORCEADD TAP..1
R 2
(-3000 1550);
FORCEPROP 3 LASTPIN (-2950 1550) SIG_NAME P5E_CPU0_P2_TX_BUF_DP<2>
J 0
(-2940 1560);
DISPLAY 0.659574 (-2940 1560);
PAINT MONO (-2940 1560);
DISPLAY INVISIBLE (-2940 1560);
FORCEPROP 1 LASTPIN (-2950 1550) BN 2
J 2
(-2938 1558);
DISPLAY 0.680851 (-2938 1558);
PAINT GREEN (-2938 1558);
FORCEPROP 2 LAST CDS_LIB standard
J 0
(-3000 1550);
DISPLAY INVISIBLE (-3000 1550);
FORCEPROP 1 LAST BODY_TYPE PLUMBING
J 2
(-3000 1600);
DISPLAY 0.872340 (-3000 1600);
PAINT GREEN (-3000 1600);
DISPLAY INVISIBLE (-3000 1600);
FORCEPROP 1 LAST HDL_TAP TRUE
J 2
(-3325 1425);
DISPLAY 0.872340 (-3325 1425);
DISPLAY INVISIBLE (-3325 1425);
FORCEPROP 1 LAST PATH I16
J 2
(-2998 1550);
DISPLAY 0.872340 (-2998 1550);
PAINT GREEN (-2998 1550);
DISPLAY INVISIBLE (-2998 1550);
FORCEADD Q_CAP_DIFFBUS..2
R 2
(-2275 500);
FORCEPROP 1 LAST LOCATION C6580
J 2
(-2000 500);
DISPLAY 0.723404 (-2000 500);
PAINT GREEN (-2000 500);
FORCEPROP 2 LAST $SEC 1
J 2
(-2100 575);
DISPLAY 0.680851 (-2100 575);
PAINT MONO (-2100 575);
DISPLAY INVISIBLE (-2100 575);
FORCEPROP 2 LAST CDS_SEC 1
J 2
(-2100 575);
DISPLAY 0.680851 (-2100 575);
DISPLAY INVISIBLE (-2100 575);
FORCEPROP 2 LASTPIN (-2200 500) $PN 1
J 0
(-2190 510);
DISPLAY 0.808511 (-2190 510);
FORCEPROP 2 LASTPIN (-2350 500) $PN 2
J 2
(-2360 510);
DISPLAY 0.808511 (-2360 510);
FORCEPROP 2 LAST VALUE DIFF BUS_0.22UF
J 2
(-2425 500);
DISPLAY 0.553191 (-2425 500);
FORCEPROP 1 LAST CDS_LMAN_SYM_OUTLINE -25,50,25,-50
J 2
(-2275 500);
DISPLAY 0.468085 (-2275 500);
PAINT GREEN (-2275 500);
DISPLAY INVISIBLE (-2275 500);
FORCEPROP 2 LAST CDS_LIB pure_quanta
J 2
(-2275 500);
DISPLAY INVISIBLE (-2275 500);
FORCEPROP 1 LAST PIN_NAMES_ROTATE TRUE
J 2
(-2275 500);
DISPLAY 0.489362 (-2275 500);
PAINT GREEN (-2275 500);
DISPLAY INVISIBLE (-2275 500);
FORCEPROP 2 LAST VOLTAGE 6.3V
J 2
(-2625 550);
DISPLAY 0.553191 (-2625 550);
DISPLAY INVISIBLE (-2625 550);
FORCEPROP 1 LAST MATERIAL X6S
J 2
(-2266 579);
DISPLAY 0.574468 (-2266 579);
PAINT GREEN (-2266 579);
DISPLAY INVISIBLE (-2266 579);
FORCEPROP 2 LAST PACK_TYPE C0201
J 2
(-2450 550);
DISPLAY 0.553191 (-2450 550);
DISPLAY INVISIBLE (-2450 550);
FORCEPROP 2 LAST TOLERANCE 20%
J 2
(-2350 550);
DISPLAY 0.553191 (-2350 550);
DISPLAY INVISIBLE (-2350 550);
FORCEPROP 1 LAST PATH I17
J 2
(-2275 500);
DISPLAY 0.723404 (-2275 500);
DISPLAY INVISIBLE (-2275 500);
FORCEPROP 1 LAST PART_NUMBER SP_CH4221MEE01
J 2
(-2391 588);
DISPLAY 0.574468 (-2391 588);
PAINT GREEN (-2391 588);
DISPLAY INVISIBLE (-2391 588);
FORCEPROP 1 LAST LOCATION C6580
J 0
(-2025 575);
DISPLAY 1.021277 (-2025 575);
DISPLAY INVISIBLE (-2025 575);
FORCEADD Q_CAP_DIFFBUS..2
R 2
(-2275 550);
FORCEPROP 1 LAST LOCATION C6579
J 2
(-2000 550);
DISPLAY 0.723404 (-2000 550);
PAINT GREEN (-2000 550);
FORCEPROP 2 LAST $SEC 1
J 2
(-2100 625);
DISPLAY 0.680851 (-2100 625);
PAINT MONO (-2100 625);
DISPLAY INVISIBLE (-2100 625);
FORCEPROP 2 LAST CDS_SEC 1
J 2
(-2100 625);
DISPLAY 0.680851 (-2100 625);
DISPLAY INVISIBLE (-2100 625);
FORCEPROP 2 LASTPIN (-2200 550) $PN 1
J 0
(-2190 560);
DISPLAY 0.808511 (-2190 560);
FORCEPROP 2 LASTPIN (-2350 550) $PN 2
J 2
(-2360 560);
DISPLAY 0.808511 (-2360 560);
FORCEPROP 2 LAST VALUE DIFF BUS_0.22UF
J 2
(-2425 550);
DISPLAY 0.553191 (-2425 550);
FORCEPROP 1 LAST CDS_LMAN_SYM_OUTLINE -25,50,25,-50
J 2
(-2275 550);
DISPLAY 0.468085 (-2275 550);
PAINT GREEN (-2275 550);
DISPLAY INVISIBLE (-2275 550);
FORCEPROP 2 LAST CDS_LIB pure_quanta
J 2
(-2275 550);
DISPLAY INVISIBLE (-2275 550);
FORCEPROP 1 LAST PIN_NAMES_ROTATE TRUE
J 2
(-2275 550);
DISPLAY 0.489362 (-2275 550);
PAINT GREEN (-2275 550);
DISPLAY INVISIBLE (-2275 550);
FORCEPROP 2 LAST VOLTAGE 6.3V
J 2
(-2625 600);
DISPLAY 0.553191 (-2625 600);
DISPLAY INVISIBLE (-2625 600);
FORCEPROP 1 LAST MATERIAL X6S
J 2
(-2266 629);
DISPLAY 0.574468 (-2266 629);
PAINT GREEN (-2266 629);
DISPLAY INVISIBLE (-2266 629);
FORCEPROP 2 LAST PACK_TYPE C0201
J 2
(-2450 600);
DISPLAY 0.553191 (-2450 600);
DISPLAY INVISIBLE (-2450 600);
FORCEPROP 2 LAST TOLERANCE 20%
J 2
(-2350 600);
DISPLAY 0.553191 (-2350 600);
DISPLAY INVISIBLE (-2350 600);
FORCEPROP 1 LAST PATH I18
J 2
(-2275 550);
DISPLAY 0.723404 (-2275 550);
DISPLAY INVISIBLE (-2275 550);
FORCEPROP 1 LAST PART_NUMBER SP_CH4221MEE01
J 2
(-2391 638);
DISPLAY 0.574468 (-2391 638);
PAINT GREEN (-2391 638);
DISPLAY INVISIBLE (-2391 638);
FORCEPROP 1 LAST LOCATION C6579
J 0
(-2025 625);
DISPLAY 1.021277 (-2025 625);
DISPLAY INVISIBLE (-2025 625);
FORCEADD Q_CAP_DIFFBUS..2
R 2
(-2275 750);
FORCEPROP 1 LAST LOCATION C6577
J 2
(-2000 750);
DISPLAY 0.723404 (-2000 750);
PAINT GREEN (-2000 750);
FORCEPROP 2 LAST $SEC 1
J 2
(-2100 825);
DISPLAY 0.680851 (-2100 825);
PAINT MONO (-2100 825);
DISPLAY INVISIBLE (-2100 825);
FORCEPROP 2 LAST CDS_SEC 1
J 2
(-2100 825);
DISPLAY 0.680851 (-2100 825);
DISPLAY INVISIBLE (-2100 825);
FORCEPROP 2 LASTPIN (-2200 750) $PN 1
J 0
(-2190 760);
DISPLAY 0.808511 (-2190 760);
FORCEPROP 2 LASTPIN (-2350 750) $PN 2
J 2
(-2360 760);
DISPLAY 0.808511 (-2360 760);
FORCEPROP 2 LAST VALUE DIFF BUS_0.22UF
J 2
(-2425 750);
DISPLAY 0.553191 (-2425 750);
FORCEPROP 2 LAST CDS_LIB pure_quanta
J 2
(-2275 750);
DISPLAY INVISIBLE (-2275 750);
FORCEPROP 1 LAST CDS_LMAN_SYM_OUTLINE -25,50,25,-50
J 2
(-2275 750);
DISPLAY 0.468085 (-2275 750);
PAINT GREEN (-2275 750);
DISPLAY INVISIBLE (-2275 750);
FORCEPROP 1 LAST PIN_NAMES_ROTATE TRUE
J 2
(-2275 750);
DISPLAY 0.489362 (-2275 750);
PAINT GREEN (-2275 750);
DISPLAY INVISIBLE (-2275 750);
FORCEPROP 2 LAST VOLTAGE 6.3V
J 2
(-2625 800);
DISPLAY 0.553191 (-2625 800);
DISPLAY INVISIBLE (-2625 800);
FORCEPROP 1 LAST MATERIAL X6S
J 2
(-2266 829);
DISPLAY 0.574468 (-2266 829);
PAINT GREEN (-2266 829);
DISPLAY INVISIBLE (-2266 829);
FORCEPROP 2 LAST PACK_TYPE C0201
J 2
(-2450 800);
DISPLAY 0.553191 (-2450 800);
DISPLAY INVISIBLE (-2450 800);
FORCEPROP 2 LAST TOLERANCE 20%
J 2
(-2350 800);
DISPLAY 0.553191 (-2350 800);
DISPLAY INVISIBLE (-2350 800);
FORCEPROP 1 LAST PATH I19
J 2
(-2275 750);
DISPLAY 0.723404 (-2275 750);
DISPLAY INVISIBLE (-2275 750);
FORCEPROP 1 LAST PART_NUMBER SP_CH4221MEE01
J 2
(-2391 838);
DISPLAY 0.574468 (-2391 838);
PAINT GREEN (-2391 838);
DISPLAY INVISIBLE (-2391 838);
FORCEPROP 1 LAST LOCATION C6577
J 0
(-2025 825);
DISPLAY 1.021277 (-2025 825);
DISPLAY INVISIBLE (-2025 825);
FORCEADD OFFPAGE..1
(-4200 1925);
FORCEPROP 2 LAST $XR0 298 
J 0
(-4482 1925);
DISPLAY 0.638298 (-4482 1925);
PAINT MONO (-4482 1925);
FORCEPROP 2 LAST CDS_LIB standard
J 0
(-4200 1925);
DISPLAY INVISIBLE (-4200 1925);
FORCEPROP 1 LAST OFFPAGE TRUE
J 0
(-3875 1800);
DISPLAY 0.872340 (-3875 1800);
DISPLAY INVISIBLE (-3875 1800);
FORCEPROP 1 LAST COMMENT_BODY TRUE
J 0
(-4075 1825);
DISPLAY 0.872340 (-4075 1825);
PAINT GREEN (-4075 1825);
DISPLAY INVISIBLE (-4075 1825);
FORCEPROP 2 LAST PATH I2
J 0
(-4450 1975);
DISPLAY 0.680851 (-4450 1975);
DISPLAY INVISIBLE (-4450 1975);
FORCEADD Q_CAP_DIFFBUS..2
R 2
(-2275 700);
FORCEPROP 1 LAST LOCATION C6578
J 2
(-2000 700);
DISPLAY 0.723404 (-2000 700);
PAINT GREEN (-2000 700);
FORCEPROP 2 LAST $SEC 1
J 2
(-2100 775);
DISPLAY 0.680851 (-2100 775);
PAINT MONO (-2100 775);
DISPLAY INVISIBLE (-2100 775);
FORCEPROP 2 LAST CDS_SEC 1
J 2
(-2100 775);
DISPLAY 0.680851 (-2100 775);
DISPLAY INVISIBLE (-2100 775);
FORCEPROP 2 LASTPIN (-2200 700) $PN 1
J 0
(-2190 710);
DISPLAY 0.808511 (-2190 710);
FORCEPROP 2 LASTPIN (-2350 700) $PN 2
J 2
(-2360 710);
DISPLAY 0.808511 (-2360 710);
FORCEPROP 2 LAST VALUE DIFF BUS_0.22UF
J 2
(-2425 700);
DISPLAY 0.553191 (-2425 700);
FORCEPROP 1 LAST CDS_LMAN_SYM_OUTLINE -25,50,25,-50
J 2
(-2275 700);
DISPLAY 0.468085 (-2275 700);
PAINT GREEN (-2275 700);
DISPLAY INVISIBLE (-2275 700);
FORCEPROP 2 LAST CDS_LIB pure_quanta
J 2
(-2275 700);
DISPLAY INVISIBLE (-2275 700);
FORCEPROP 1 LAST PIN_NAMES_ROTATE TRUE
J 2
(-2275 700);
DISPLAY 0.489362 (-2275 700);
PAINT GREEN (-2275 700);
DISPLAY INVISIBLE (-2275 700);
FORCEPROP 2 LAST VOLTAGE 6.3V
J 2
(-2625 750);
DISPLAY 0.553191 (-2625 750);
DISPLAY INVISIBLE (-2625 750);
FORCEPROP 1 LAST MATERIAL X6S
J 2
(-2266 779);
DISPLAY 0.574468 (-2266 779);
PAINT GREEN (-2266 779);
DISPLAY INVISIBLE (-2266 779);
FORCEPROP 2 LAST PACK_TYPE C0201
J 2
(-2450 750);
DISPLAY 0.553191 (-2450 750);
DISPLAY INVISIBLE (-2450 750);
FORCEPROP 2 LAST TOLERANCE 20%
J 2
(-2350 750);
DISPLAY 0.553191 (-2350 750);
DISPLAY INVISIBLE (-2350 750);
FORCEPROP 1 LAST PATH I20
J 2
(-2275 700);
DISPLAY 0.723404 (-2275 700);
DISPLAY INVISIBLE (-2275 700);
FORCEPROP 1 LAST PART_NUMBER SP_CH4221MEE01
J 2
(-2391 788);
DISPLAY 0.574468 (-2391 788);
PAINT GREEN (-2391 788);
DISPLAY INVISIBLE (-2391 788);
FORCEPROP 1 LAST LOCATION C6578
J 0
(-2025 775);
DISPLAY 1.021277 (-2025 775);
DISPLAY INVISIBLE (-2025 775);
FORCEADD TAP..1
(-1525 500);
FORCEPROP 3 LASTPIN (-1575 500) SIG_NAME P5E_CPU0_P2_TX_BUF_C_DN<7>
J 0
(-1565 510);
DISPLAY 0.659574 (-1565 510);
PAINT MONO (-1565 510);
DISPLAY INVISIBLE (-1565 510);
FORCEPROP 1 LASTPIN (-1575 500) BN 7
J 0
(-1587 508);
DISPLAY 0.680851 (-1587 508);
PAINT GREEN (-1587 508);
FORCEPROP 2 LAST CDS_LIB standard
J 0
(-1525 500);
DISPLAY INVISIBLE (-1525 500);
FORCEPROP 1 LAST BODY_TYPE PLUMBING
J 0
(-1525 550);
DISPLAY 0.872340 (-1525 550);
PAINT GREEN (-1525 550);
DISPLAY INVISIBLE (-1525 550);
FORCEPROP 1 LAST HDL_TAP TRUE
J 0
(-1200 375);
DISPLAY 0.872340 (-1200 375);
DISPLAY INVISIBLE (-1200 375);
FORCEPROP 1 LAST PATH I21
J 0
(-1527 500);
DISPLAY 0.872340 (-1527 500);
PAINT GREEN (-1527 500);
DISPLAY INVISIBLE (-1527 500);
FORCEADD TAP..1
(-1725 550);
FORCEPROP 3 LASTPIN (-1775 550) SIG_NAME P5E_CPU0_P2_TX_BUF_C_DP<7>
J 0
(-1765 560);
DISPLAY 0.659574 (-1765 560);
PAINT MONO (-1765 560);
DISPLAY INVISIBLE (-1765 560);
FORCEPROP 1 LASTPIN (-1775 550) BN 7
J 0
(-1787 558);
DISPLAY 0.680851 (-1787 558);
PAINT GREEN (-1787 558);
FORCEPROP 2 LAST CDS_LIB standard
J 0
(-1725 550);
DISPLAY INVISIBLE (-1725 550);
FORCEPROP 1 LAST BODY_TYPE PLUMBING
J 0
(-1725 600);
DISPLAY 0.872340 (-1725 600);
PAINT GREEN (-1725 600);
DISPLAY INVISIBLE (-1725 600);
FORCEPROP 1 LAST HDL_TAP TRUE
J 0
(-1400 425);
DISPLAY 0.872340 (-1400 425);
DISPLAY INVISIBLE (-1400 425);
FORCEPROP 1 LAST PATH I22
J 0
(-1727 550);
DISPLAY 0.872340 (-1727 550);
PAINT GREEN (-1727 550);
DISPLAY INVISIBLE (-1727 550);
FORCEADD TAP..1
(-1725 750);
FORCEPROP 3 LASTPIN (-1775 750) SIG_NAME P5E_CPU0_P2_TX_BUF_C_DP<6>
J 0
(-1765 760);
DISPLAY 0.659574 (-1765 760);
PAINT MONO (-1765 760);
DISPLAY INVISIBLE (-1765 760);
FORCEPROP 1 LASTPIN (-1775 750) BN 6
J 0
(-1787 758);
DISPLAY 0.680851 (-1787 758);
PAINT GREEN (-1787 758);
FORCEPROP 2 LAST CDS_LIB standard
J 0
(-1725 750);
DISPLAY INVISIBLE (-1725 750);
FORCEPROP 1 LAST BODY_TYPE PLUMBING
J 0
(-1725 800);
DISPLAY 0.872340 (-1725 800);
PAINT GREEN (-1725 800);
DISPLAY INVISIBLE (-1725 800);
FORCEPROP 1 LAST HDL_TAP TRUE
J 0
(-1400 625);
DISPLAY 0.872340 (-1400 625);
DISPLAY INVISIBLE (-1400 625);
FORCEPROP 1 LAST PATH I23
J 0
(-1727 750);
DISPLAY 0.872340 (-1727 750);
PAINT GREEN (-1727 750);
DISPLAY INVISIBLE (-1727 750);
FORCEADD TAP..1
(-1525 700);
FORCEPROP 3 LASTPIN (-1575 700) SIG_NAME P5E_CPU0_P2_TX_BUF_C_DN<6>
J 0
(-1565 710);
DISPLAY 0.659574 (-1565 710);
PAINT MONO (-1565 710);
DISPLAY INVISIBLE (-1565 710);
FORCEPROP 1 LASTPIN (-1575 700) BN 6
J 0
(-1587 708);
DISPLAY 0.680851 (-1587 708);
PAINT GREEN (-1587 708);
FORCEPROP 2 LAST CDS_LIB standard
J 0
(-1525 700);
DISPLAY INVISIBLE (-1525 700);
FORCEPROP 1 LAST BODY_TYPE PLUMBING
J 0
(-1525 750);
DISPLAY 0.872340 (-1525 750);
PAINT GREEN (-1525 750);
DISPLAY INVISIBLE (-1525 750);
FORCEPROP 1 LAST HDL_TAP TRUE
J 0
(-1200 575);
DISPLAY 0.872340 (-1200 575);
DISPLAY INVISIBLE (-1200 575);
FORCEPROP 1 LAST PATH I24
J 0
(-1527 700);
DISPLAY 0.872340 (-1527 700);
PAINT GREEN (-1527 700);
DISPLAY INVISIBLE (-1527 700);
FORCEADD Q_CAP_DIFFBUS..2
R 2
(-2275 950);
FORCEPROP 1 LAST LOCATION C6575
J 2
(-2000 950);
DISPLAY 0.723404 (-2000 950);
PAINT GREEN (-2000 950);
FORCEPROP 2 LAST $SEC 1
J 2
(-2100 1025);
DISPLAY 0.680851 (-2100 1025);
PAINT MONO (-2100 1025);
DISPLAY INVISIBLE (-2100 1025);
FORCEPROP 2 LAST CDS_SEC 1
J 2
(-2100 1025);
DISPLAY 0.680851 (-2100 1025);
DISPLAY INVISIBLE (-2100 1025);
FORCEPROP 2 LASTPIN (-2200 950) $PN 1
J 0
(-2190 960);
DISPLAY 0.808511 (-2190 960);
FORCEPROP 2 LASTPIN (-2350 950) $PN 2
J 2
(-2360 960);
DISPLAY 0.808511 (-2360 960);
FORCEPROP 2 LAST VALUE DIFF BUS_0.22UF
J 2
(-2425 950);
DISPLAY 0.553191 (-2425 950);
FORCEPROP 1 LAST CDS_LMAN_SYM_OUTLINE -25,50,25,-50
J 2
(-2275 950);
DISPLAY 0.468085 (-2275 950);
PAINT GREEN (-2275 950);
DISPLAY INVISIBLE (-2275 950);
FORCEPROP 2 LAST CDS_LIB pure_quanta
J 2
(-2275 950);
DISPLAY INVISIBLE (-2275 950);
FORCEPROP 1 LAST PIN_NAMES_ROTATE TRUE
J 2
(-2275 950);
DISPLAY 0.489362 (-2275 950);
PAINT GREEN (-2275 950);
DISPLAY INVISIBLE (-2275 950);
FORCEPROP 2 LAST VOLTAGE 6.3V
J 2
(-2625 1000);
DISPLAY 0.553191 (-2625 1000);
DISPLAY INVISIBLE (-2625 1000);
FORCEPROP 1 LAST MATERIAL X6S
J 2
(-2266 1029);
DISPLAY 0.574468 (-2266 1029);
PAINT GREEN (-2266 1029);
DISPLAY INVISIBLE (-2266 1029);
FORCEPROP 2 LAST PACK_TYPE C0201
J 2
(-2450 1000);
DISPLAY 0.553191 (-2450 1000);
DISPLAY INVISIBLE (-2450 1000);
FORCEPROP 2 LAST TOLERANCE 20%
J 2
(-2350 1000);
DISPLAY 0.553191 (-2350 1000);
DISPLAY INVISIBLE (-2350 1000);
FORCEPROP 1 LAST PATH I25
J 2
(-2275 950);
DISPLAY 0.723404 (-2275 950);
DISPLAY INVISIBLE (-2275 950);
FORCEPROP 1 LAST PART_NUMBER SP_CH4221MEE01
J 2
(-2391 1038);
DISPLAY 0.574468 (-2391 1038);
PAINT GREEN (-2391 1038);
DISPLAY INVISIBLE (-2391 1038);
FORCEPROP 1 LAST LOCATION C6575
J 0
(-2025 1025);
DISPLAY 1.021277 (-2025 1025);
DISPLAY INVISIBLE (-2025 1025);
FORCEADD Q_CAP_DIFFBUS..2
R 2
(-2275 900);
FORCEPROP 1 LAST LOCATION C6576
J 2
(-2000 900);
DISPLAY 0.723404 (-2000 900);
PAINT GREEN (-2000 900);
FORCEPROP 2 LAST $SEC 1
J 2
(-2100 975);
DISPLAY 0.680851 (-2100 975);
PAINT MONO (-2100 975);
DISPLAY INVISIBLE (-2100 975);
FORCEPROP 2 LAST CDS_SEC 1
J 2
(-2100 975);
DISPLAY 0.680851 (-2100 975);
DISPLAY INVISIBLE (-2100 975);
FORCEPROP 2 LASTPIN (-2200 900) $PN 1
J 0
(-2190 910);
DISPLAY 0.808511 (-2190 910);
FORCEPROP 2 LASTPIN (-2350 900) $PN 2
J 2
(-2360 910);
DISPLAY 0.808511 (-2360 910);
FORCEPROP 2 LAST VALUE DIFF BUS_0.22UF
J 2
(-2425 900);
DISPLAY 0.553191 (-2425 900);
FORCEPROP 1 LAST CDS_LMAN_SYM_OUTLINE -25,50,25,-50
J 2
(-2275 900);
DISPLAY 0.468085 (-2275 900);
PAINT GREEN (-2275 900);
DISPLAY INVISIBLE (-2275 900);
FORCEPROP 2 LAST CDS_LIB pure_quanta
J 2
(-2275 900);
DISPLAY INVISIBLE (-2275 900);
FORCEPROP 1 LAST PIN_NAMES_ROTATE TRUE
J 2
(-2275 900);
DISPLAY 0.489362 (-2275 900);
PAINT GREEN (-2275 900);
DISPLAY INVISIBLE (-2275 900);
FORCEPROP 2 LAST VOLTAGE 6.3V
J 2
(-2625 950);
DISPLAY 0.553191 (-2625 950);
DISPLAY INVISIBLE (-2625 950);
FORCEPROP 1 LAST MATERIAL X6S
J 2
(-2266 979);
DISPLAY 0.574468 (-2266 979);
PAINT GREEN (-2266 979);
DISPLAY INVISIBLE (-2266 979);
FORCEPROP 2 LAST PACK_TYPE C0201
J 2
(-2450 950);
DISPLAY 0.553191 (-2450 950);
DISPLAY INVISIBLE (-2450 950);
FORCEPROP 2 LAST TOLERANCE 20%
J 2
(-2350 950);
DISPLAY 0.553191 (-2350 950);
DISPLAY INVISIBLE (-2350 950);
FORCEPROP 1 LAST PATH I26
J 2
(-2275 900);
DISPLAY 0.723404 (-2275 900);
DISPLAY INVISIBLE (-2275 900);
FORCEPROP 1 LAST PART_NUMBER SP_CH4221MEE01
J 2
(-2391 988);
DISPLAY 0.574468 (-2391 988);
PAINT GREEN (-2391 988);
DISPLAY INVISIBLE (-2391 988);
FORCEPROP 1 LAST LOCATION C6576
J 0
(-2025 975);
DISPLAY 1.021277 (-2025 975);
DISPLAY INVISIBLE (-2025 975);
FORCEADD Q_CAP_DIFFBUS..2
R 2
(-2275 1150);
FORCEPROP 1 LAST LOCATION C6573
J 2
(-2000 1150);
DISPLAY 0.723404 (-2000 1150);
PAINT GREEN (-2000 1150);
FORCEPROP 2 LAST $SEC 1
J 2
(-2100 1225);
DISPLAY 0.680851 (-2100 1225);
PAINT MONO (-2100 1225);
DISPLAY INVISIBLE (-2100 1225);
FORCEPROP 2 LAST CDS_SEC 1
J 2
(-2100 1225);
DISPLAY 0.680851 (-2100 1225);
DISPLAY INVISIBLE (-2100 1225);
FORCEPROP 2 LASTPIN (-2200 1150) $PN 1
J 0
(-2190 1160);
DISPLAY 0.808511 (-2190 1160);
FORCEPROP 2 LASTPIN (-2350 1150) $PN 2
J 2
(-2360 1160);
DISPLAY 0.808511 (-2360 1160);
FORCEPROP 2 LAST VALUE DIFF BUS_0.22UF
J 2
(-2425 1150);
DISPLAY 0.553191 (-2425 1150);
FORCEPROP 2 LAST CDS_LIB pure_quanta
J 2
(-2275 1150);
DISPLAY INVISIBLE (-2275 1150);
FORCEPROP 1 LAST CDS_LMAN_SYM_OUTLINE -25,50,25,-50
J 2
(-2275 1150);
DISPLAY 0.468085 (-2275 1150);
PAINT GREEN (-2275 1150);
DISPLAY INVISIBLE (-2275 1150);
FORCEPROP 1 LAST PIN_NAMES_ROTATE TRUE
J 2
(-2275 1150);
DISPLAY 0.489362 (-2275 1150);
PAINT GREEN (-2275 1150);
DISPLAY INVISIBLE (-2275 1150);
FORCEPROP 2 LAST VOLTAGE 6.3V
J 2
(-2625 1200);
DISPLAY 0.553191 (-2625 1200);
DISPLAY INVISIBLE (-2625 1200);
FORCEPROP 1 LAST MATERIAL X6S
J 2
(-2266 1229);
DISPLAY 0.574468 (-2266 1229);
PAINT GREEN (-2266 1229);
DISPLAY INVISIBLE (-2266 1229);
FORCEPROP 2 LAST PACK_TYPE C0201
J 2
(-2450 1200);
DISPLAY 0.553191 (-2450 1200);
DISPLAY INVISIBLE (-2450 1200);
FORCEPROP 2 LAST TOLERANCE 20%
J 2
(-2350 1200);
DISPLAY 0.553191 (-2350 1200);
DISPLAY INVISIBLE (-2350 1200);
FORCEPROP 1 LAST PATH I27
J 2
(-2275 1150);
DISPLAY 0.723404 (-2275 1150);
DISPLAY INVISIBLE (-2275 1150);
FORCEPROP 1 LAST PART_NUMBER SP_CH4221MEE01
J 2
(-2391 1238);
DISPLAY 0.574468 (-2391 1238);
PAINT GREEN (-2391 1238);
DISPLAY INVISIBLE (-2391 1238);
FORCEPROP 1 LAST LOCATION C6573
J 0
(-2025 1225);
DISPLAY 1.021277 (-2025 1225);
DISPLAY INVISIBLE (-2025 1225);
FORCEADD Q_CAP_DIFFBUS..2
R 2
(-2275 1100);
FORCEPROP 1 LAST LOCATION C6574
J 2
(-2000 1100);
DISPLAY 0.723404 (-2000 1100);
PAINT GREEN (-2000 1100);
FORCEPROP 2 LAST $SEC 1
J 2
(-2100 1175);
DISPLAY 0.680851 (-2100 1175);
PAINT MONO (-2100 1175);
DISPLAY INVISIBLE (-2100 1175);
FORCEPROP 2 LAST CDS_SEC 1
J 2
(-2100 1175);
DISPLAY 0.680851 (-2100 1175);
DISPLAY INVISIBLE (-2100 1175);
FORCEPROP 2 LASTPIN (-2200 1100) $PN 1
J 0
(-2190 1110);
DISPLAY 0.808511 (-2190 1110);
FORCEPROP 2 LASTPIN (-2350 1100) $PN 2
J 2
(-2360 1110);
DISPLAY 0.808511 (-2360 1110);
FORCEPROP 2 LAST VALUE DIFF BUS_0.22UF
J 2
(-2425 1100);
DISPLAY 0.553191 (-2425 1100);
FORCEPROP 2 LAST CDS_LIB pure_quanta
J 2
(-2275 1100);
DISPLAY INVISIBLE (-2275 1100);
FORCEPROP 1 LAST CDS_LMAN_SYM_OUTLINE -25,50,25,-50
J 2
(-2275 1100);
DISPLAY 0.468085 (-2275 1100);
PAINT GREEN (-2275 1100);
DISPLAY INVISIBLE (-2275 1100);
FORCEPROP 1 LAST PIN_NAMES_ROTATE TRUE
J 2
(-2275 1100);
DISPLAY 0.489362 (-2275 1100);
PAINT GREEN (-2275 1100);
DISPLAY INVISIBLE (-2275 1100);
FORCEPROP 2 LAST VOLTAGE 6.3V
J 2
(-2625 1150);
DISPLAY 0.553191 (-2625 1150);
DISPLAY INVISIBLE (-2625 1150);
FORCEPROP 1 LAST MATERIAL X6S
J 2
(-2266 1179);
DISPLAY 0.574468 (-2266 1179);
PAINT GREEN (-2266 1179);
DISPLAY INVISIBLE (-2266 1179);
FORCEPROP 2 LAST PACK_TYPE C0201
J 2
(-2450 1150);
DISPLAY 0.553191 (-2450 1150);
DISPLAY INVISIBLE (-2450 1150);
FORCEPROP 2 LAST TOLERANCE 20%
J 2
(-2350 1150);
DISPLAY 0.553191 (-2350 1150);
DISPLAY INVISIBLE (-2350 1150);
FORCEPROP 1 LAST PATH I28
J 2
(-2275 1100);
DISPLAY 0.723404 (-2275 1100);
DISPLAY INVISIBLE (-2275 1100);
FORCEPROP 1 LAST PART_NUMBER SP_CH4221MEE01
J 2
(-2391 1188);
DISPLAY 0.574468 (-2391 1188);
PAINT GREEN (-2391 1188);
DISPLAY INVISIBLE (-2391 1188);
FORCEPROP 1 LAST LOCATION C6574
J 0
(-2025 1175);
DISPLAY 1.021277 (-2025 1175);
DISPLAY INVISIBLE (-2025 1175);
FORCEADD Q_CAP_DIFFBUS..2
R 2
(-2275 1300);
FORCEPROP 1 LAST LOCATION C6572
J 2
(-2000 1300);
DISPLAY 0.723404 (-2000 1300);
PAINT GREEN (-2000 1300);
FORCEPROP 2 LAST $SEC 1
J 2
(-2100 1375);
DISPLAY 0.680851 (-2100 1375);
PAINT MONO (-2100 1375);
DISPLAY INVISIBLE (-2100 1375);
FORCEPROP 2 LAST CDS_SEC 1
J 2
(-2100 1375);
DISPLAY 0.680851 (-2100 1375);
DISPLAY INVISIBLE (-2100 1375);
FORCEPROP 2 LASTPIN (-2200 1300) $PN 1
J 0
(-2190 1310);
DISPLAY 0.808511 (-2190 1310);
FORCEPROP 2 LASTPIN (-2350 1300) $PN 2
J 2
(-2360 1310);
DISPLAY 0.808511 (-2360 1310);
FORCEPROP 2 LAST VALUE DIFF BUS_0.22UF
J 2
(-2425 1300);
DISPLAY 0.553191 (-2425 1300);
FORCEPROP 1 LAST CDS_LMAN_SYM_OUTLINE -25,50,25,-50
J 2
(-2275 1300);
DISPLAY 0.468085 (-2275 1300);
PAINT GREEN (-2275 1300);
DISPLAY INVISIBLE (-2275 1300);
FORCEPROP 2 LAST CDS_LIB pure_quanta
J 2
(-2275 1300);
DISPLAY INVISIBLE (-2275 1300);
FORCEPROP 1 LAST PIN_NAMES_ROTATE TRUE
J 2
(-2275 1300);
DISPLAY 0.489362 (-2275 1300);
PAINT GREEN (-2275 1300);
DISPLAY INVISIBLE (-2275 1300);
FORCEPROP 2 LAST VOLTAGE 6.3V
J 2
(-2625 1350);
DISPLAY 0.553191 (-2625 1350);
DISPLAY INVISIBLE (-2625 1350);
FORCEPROP 1 LAST MATERIAL X6S
J 2
(-2266 1379);
DISPLAY 0.574468 (-2266 1379);
PAINT GREEN (-2266 1379);
DISPLAY INVISIBLE (-2266 1379);
FORCEPROP 2 LAST PACK_TYPE C0201
J 2
(-2450 1350);
DISPLAY 0.553191 (-2450 1350);
DISPLAY INVISIBLE (-2450 1350);
FORCEPROP 2 LAST TOLERANCE 20%
J 2
(-2350 1350);
DISPLAY 0.553191 (-2350 1350);
DISPLAY INVISIBLE (-2350 1350);
FORCEPROP 1 LAST PATH I29
J 2
(-2275 1300);
DISPLAY 0.723404 (-2275 1300);
DISPLAY INVISIBLE (-2275 1300);
FORCEPROP 1 LAST PART_NUMBER SP_CH4221MEE01
J 2
(-2391 1388);
DISPLAY 0.574468 (-2391 1388);
PAINT GREEN (-2391 1388);
DISPLAY INVISIBLE (-2391 1388);
FORCEPROP 1 LAST LOCATION C6572
J 0
(-2025 1375);
DISPLAY 1.021277 (-2025 1375);
DISPLAY INVISIBLE (-2025 1375);
FORCEADD TAP..1
R 2
(-3250 500);
FORCEPROP 3 LASTPIN (-3200 500) SIG_NAME P5E_CPU0_P2_TX_BUF_DN<7>
J 0
(-3190 510);
DISPLAY 0.659574 (-3190 510);
PAINT MONO (-3190 510);
DISPLAY INVISIBLE (-3190 510);
FORCEPROP 1 LASTPIN (-3200 500) BN 7
J 2
(-3188 508);
DISPLAY 0.680851 (-3188 508);
PAINT GREEN (-3188 508);
FORCEPROP 2 LAST CDS_LIB standard
J 0
(-3250 500);
DISPLAY INVISIBLE (-3250 500);
FORCEPROP 1 LAST BODY_TYPE PLUMBING
J 2
(-3250 550);
DISPLAY 0.872340 (-3250 550);
PAINT GREEN (-3250 550);
DISPLAY INVISIBLE (-3250 550);
FORCEPROP 1 LAST HDL_TAP TRUE
J 2
(-3575 375);
DISPLAY 0.872340 (-3575 375);
DISPLAY INVISIBLE (-3575 375);
FORCEPROP 1 LAST PATH I3
J 2
(-3248 500);
DISPLAY 0.872340 (-3248 500);
PAINT GREEN (-3248 500);
DISPLAY INVISIBLE (-3248 500);
FORCEADD Q_CAP_DIFFBUS..2
R 2
(-2275 1350);
FORCEPROP 1 LAST LOCATION C6571
J 2
(-2000 1350);
DISPLAY 0.723404 (-2000 1350);
PAINT GREEN (-2000 1350);
FORCEPROP 2 LAST $SEC 1
J 2
(-2100 1425);
DISPLAY 0.680851 (-2100 1425);
PAINT MONO (-2100 1425);
DISPLAY INVISIBLE (-2100 1425);
FORCEPROP 2 LAST CDS_SEC 1
J 2
(-2100 1425);
DISPLAY 0.680851 (-2100 1425);
DISPLAY INVISIBLE (-2100 1425);
FORCEPROP 2 LASTPIN (-2200 1350) $PN 1
J 0
(-2190 1360);
DISPLAY 0.808511 (-2190 1360);
FORCEPROP 2 LASTPIN (-2350 1350) $PN 2
J 2
(-2360 1360);
DISPLAY 0.808511 (-2360 1360);
FORCEPROP 2 LAST VALUE DIFF BUS_0.22UF
J 2
(-2425 1350);
DISPLAY 0.553191 (-2425 1350);
FORCEPROP 1 LAST CDS_LMAN_SYM_OUTLINE -25,50,25,-50
J 2
(-2275 1350);
DISPLAY 0.468085 (-2275 1350);
PAINT GREEN (-2275 1350);
DISPLAY INVISIBLE (-2275 1350);
FORCEPROP 2 LAST CDS_LIB pure_quanta
J 2
(-2275 1350);
DISPLAY INVISIBLE (-2275 1350);
FORCEPROP 1 LAST PIN_NAMES_ROTATE TRUE
J 2
(-2275 1350);
DISPLAY 0.489362 (-2275 1350);
PAINT GREEN (-2275 1350);
DISPLAY INVISIBLE (-2275 1350);
FORCEPROP 2 LAST VOLTAGE 6.3V
J 2
(-2625 1400);
DISPLAY 0.553191 (-2625 1400);
DISPLAY INVISIBLE (-2625 1400);
FORCEPROP 1 LAST MATERIAL X6S
J 2
(-2266 1429);
DISPLAY 0.574468 (-2266 1429);
PAINT GREEN (-2266 1429);
DISPLAY INVISIBLE (-2266 1429);
FORCEPROP 2 LAST PACK_TYPE C0201
J 2
(-2450 1400);
DISPLAY 0.553191 (-2450 1400);
DISPLAY INVISIBLE (-2450 1400);
FORCEPROP 2 LAST TOLERANCE 20%
J 2
(-2350 1400);
DISPLAY 0.553191 (-2350 1400);
DISPLAY INVISIBLE (-2350 1400);
FORCEPROP 1 LAST PATH I30
J 2
(-2275 1350);
DISPLAY 0.723404 (-2275 1350);
DISPLAY INVISIBLE (-2275 1350);
FORCEPROP 1 LAST PART_NUMBER SP_CH4221MEE01
J 2
(-2391 1438);
DISPLAY 0.574468 (-2391 1438);
PAINT GREEN (-2391 1438);
DISPLAY INVISIBLE (-2391 1438);
FORCEPROP 1 LAST LOCATION C6571
J 0
(-2025 1425);
DISPLAY 1.021277 (-2025 1425);
DISPLAY INVISIBLE (-2025 1425);
FORCEADD Q_CAP_DIFFBUS..2
R 2
(-2275 1500);
FORCEPROP 1 LAST LOCATION C6570
J 2
(-2000 1500);
DISPLAY 0.723404 (-2000 1500);
PAINT GREEN (-2000 1500);
FORCEPROP 2 LAST $SEC 1
J 2
(-2100 1575);
DISPLAY 0.680851 (-2100 1575);
PAINT MONO (-2100 1575);
DISPLAY INVISIBLE (-2100 1575);
FORCEPROP 2 LAST CDS_SEC 1
J 2
(-2100 1575);
DISPLAY 0.680851 (-2100 1575);
DISPLAY INVISIBLE (-2100 1575);
FORCEPROP 2 LASTPIN (-2200 1500) $PN 1
J 0
(-2190 1510);
DISPLAY 0.808511 (-2190 1510);
FORCEPROP 2 LASTPIN (-2350 1500) $PN 2
J 2
(-2360 1510);
DISPLAY 0.808511 (-2360 1510);
FORCEPROP 2 LAST VALUE DIFF BUS_0.22UF
J 2
(-2425 1500);
DISPLAY 0.553191 (-2425 1500);
FORCEPROP 1 LAST CDS_LMAN_SYM_OUTLINE -25,50,25,-50
J 2
(-2275 1500);
DISPLAY 0.468085 (-2275 1500);
PAINT GREEN (-2275 1500);
DISPLAY INVISIBLE (-2275 1500);
FORCEPROP 2 LAST CDS_LIB pure_quanta
J 2
(-2275 1500);
DISPLAY INVISIBLE (-2275 1500);
FORCEPROP 1 LAST PIN_NAMES_ROTATE TRUE
J 2
(-2275 1500);
DISPLAY 0.489362 (-2275 1500);
PAINT GREEN (-2275 1500);
DISPLAY INVISIBLE (-2275 1500);
FORCEPROP 2 LAST VOLTAGE 6.3V
J 2
(-2625 1550);
DISPLAY 0.553191 (-2625 1550);
DISPLAY INVISIBLE (-2625 1550);
FORCEPROP 1 LAST MATERIAL X6S
J 2
(-2266 1579);
DISPLAY 0.574468 (-2266 1579);
PAINT GREEN (-2266 1579);
DISPLAY INVISIBLE (-2266 1579);
FORCEPROP 2 LAST PACK_TYPE C0201
J 2
(-2450 1550);
DISPLAY 0.553191 (-2450 1550);
DISPLAY INVISIBLE (-2450 1550);
FORCEPROP 2 LAST TOLERANCE 20%
J 2
(-2350 1550);
DISPLAY 0.553191 (-2350 1550);
DISPLAY INVISIBLE (-2350 1550);
FORCEPROP 1 LAST PATH I31
J 2
(-2275 1500);
DISPLAY 0.723404 (-2275 1500);
DISPLAY INVISIBLE (-2275 1500);
FORCEPROP 1 LAST PART_NUMBER SP_CH4221MEE01
J 2
(-2391 1588);
DISPLAY 0.574468 (-2391 1588);
PAINT GREEN (-2391 1588);
DISPLAY INVISIBLE (-2391 1588);
FORCEPROP 1 LAST LOCATION C6570
J 0
(-2025 1575);
DISPLAY 1.021277 (-2025 1575);
DISPLAY INVISIBLE (-2025 1575);
FORCEADD Q_CAP_DIFFBUS..2
R 2
(-2275 1750);
FORCEPROP 1 LAST LOCATION C6567
J 2
(-1975 1750);
DISPLAY 0.723404 (-1975 1750);
PAINT GREEN (-1975 1750);
FORCEPROP 2 LAST $SEC 1
J 2
(-2100 1825);
DISPLAY 0.680851 (-2100 1825);
PAINT MONO (-2100 1825);
DISPLAY INVISIBLE (-2100 1825);
FORCEPROP 2 LAST CDS_SEC 1
J 2
(-2100 1825);
DISPLAY 0.680851 (-2100 1825);
DISPLAY INVISIBLE (-2100 1825);
FORCEPROP 2 LASTPIN (-2200 1750) $PN 1
J 0
(-2190 1760);
DISPLAY 0.808511 (-2190 1760);
FORCEPROP 2 LASTPIN (-2350 1750) $PN 2
J 2
(-2360 1760);
DISPLAY 0.808511 (-2360 1760);
FORCEPROP 2 LAST VALUE DIFF BUS_0.22UF
J 2
(-2425 1750);
DISPLAY 0.553191 (-2425 1750);
FORCEPROP 2 LAST TOLERANCE 20%
J 2
(-2350 1800);
DISPLAY 0.553191 (-2350 1800);
DISPLAY INVISIBLE (-2350 1800);
FORCEPROP 2 LAST PACK_TYPE C0201
J 2
(-2450 1800);
DISPLAY 0.553191 (-2450 1800);
DISPLAY INVISIBLE (-2450 1800);
FORCEPROP 1 LAST MATERIAL X6S
J 2
(-2266 1829);
DISPLAY 0.574468 (-2266 1829);
PAINT GREEN (-2266 1829);
DISPLAY INVISIBLE (-2266 1829);
FORCEPROP 2 LAST VOLTAGE 6.3V
J 2
(-2625 1800);
DISPLAY 0.553191 (-2625 1800);
DISPLAY INVISIBLE (-2625 1800);
FORCEPROP 1 LAST PIN_NAMES_ROTATE TRUE
J 2
(-2275 1750);
DISPLAY 0.489362 (-2275 1750);
PAINT GREEN (-2275 1750);
DISPLAY INVISIBLE (-2275 1750);
FORCEPROP 2 LAST CDS_LIB pure_quanta
J 2
(-2275 1750);
DISPLAY INVISIBLE (-2275 1750);
FORCEPROP 1 LAST CDS_LMAN_SYM_OUTLINE -25,50,25,-50
J 2
(-2275 1750);
DISPLAY 0.468085 (-2275 1750);
PAINT GREEN (-2275 1750);
DISPLAY INVISIBLE (-2275 1750);
FORCEPROP 1 LAST PATH I32
J 2
(-2275 1750);
DISPLAY 0.723404 (-2275 1750);
DISPLAY INVISIBLE (-2275 1750);
FORCEPROP 1 LAST PART_NUMBER SP_CH4221MEE01
J 2
(-2391 1838);
DISPLAY 0.574468 (-2391 1838);
PAINT GREEN (-2391 1838);
DISPLAY INVISIBLE (-2391 1838);
FORCEPROP 1 LAST LOCATION C6567
J 0
(-2025 1825);
DISPLAY 1.021277 (-2025 1825);
DISPLAY INVISIBLE (-2025 1825);
FORCEADD Q_CAP_DIFFBUS..2
R 2
(-2275 1700);
FORCEPROP 1 LAST LOCATION C6568
J 2
(-1975 1700);
DISPLAY 0.723404 (-1975 1700);
PAINT GREEN (-1975 1700);
FORCEPROP 2 LAST $SEC 1
J 2
(-2100 1775);
DISPLAY 0.680851 (-2100 1775);
PAINT MONO (-2100 1775);
DISPLAY INVISIBLE (-2100 1775);
FORCEPROP 2 LAST CDS_SEC 1
J 2
(-2100 1775);
DISPLAY 0.680851 (-2100 1775);
DISPLAY INVISIBLE (-2100 1775);
FORCEPROP 2 LASTPIN (-2200 1700) $PN 1
J 0
(-2190 1710);
DISPLAY 0.808511 (-2190 1710);
FORCEPROP 2 LASTPIN (-2350 1700) $PN 2
J 2
(-2360 1710);
DISPLAY 0.808511 (-2360 1710);
FORCEPROP 2 LAST VALUE DIFF BUS_0.22UF
J 2
(-2425 1700);
DISPLAY 0.553191 (-2425 1700);
FORCEPROP 1 LAST CDS_LMAN_SYM_OUTLINE -25,50,25,-50
J 2
(-2275 1700);
DISPLAY 0.468085 (-2275 1700);
PAINT GREEN (-2275 1700);
DISPLAY INVISIBLE (-2275 1700);
FORCEPROP 2 LAST CDS_LIB pure_quanta
J 2
(-2275 1700);
DISPLAY INVISIBLE (-2275 1700);
FORCEPROP 1 LAST PIN_NAMES_ROTATE TRUE
J 2
(-2275 1700);
DISPLAY 0.489362 (-2275 1700);
PAINT GREEN (-2275 1700);
DISPLAY INVISIBLE (-2275 1700);
FORCEPROP 2 LAST VOLTAGE 6.3V
J 2
(-2625 1750);
DISPLAY 0.553191 (-2625 1750);
DISPLAY INVISIBLE (-2625 1750);
FORCEPROP 1 LAST MATERIAL X6S
J 2
(-2266 1779);
DISPLAY 0.574468 (-2266 1779);
PAINT GREEN (-2266 1779);
DISPLAY INVISIBLE (-2266 1779);
FORCEPROP 2 LAST PACK_TYPE C0201
J 2
(-2450 1750);
DISPLAY 0.553191 (-2450 1750);
DISPLAY INVISIBLE (-2450 1750);
FORCEPROP 2 LAST TOLERANCE 20%
J 2
(-2350 1750);
DISPLAY 0.553191 (-2350 1750);
DISPLAY INVISIBLE (-2350 1750);
FORCEPROP 1 LAST PATH I33
J 2
(-2275 1700);
DISPLAY 0.723404 (-2275 1700);
DISPLAY INVISIBLE (-2275 1700);
FORCEPROP 1 LAST PART_NUMBER SP_CH4221MEE01
J 2
(-2391 1788);
DISPLAY 0.574468 (-2391 1788);
PAINT GREEN (-2391 1788);
DISPLAY INVISIBLE (-2391 1788);
FORCEPROP 1 LAST LOCATION C6568
J 0
(-2025 1775);
DISPLAY 1.021277 (-2025 1775);
DISPLAY INVISIBLE (-2025 1775);
FORCEADD Q_CAP_DIFFBUS..2
R 2
(-2275 1550);
FORCEPROP 1 LAST LOCATION C6569
J 2
(-2000 1550);
DISPLAY 0.723404 (-2000 1550);
PAINT GREEN (-2000 1550);
FORCEPROP 2 LAST $SEC 1
J 2
(-2100 1625);
DISPLAY 0.680851 (-2100 1625);
PAINT MONO (-2100 1625);
DISPLAY INVISIBLE (-2100 1625);
FORCEPROP 2 LAST CDS_SEC 1
J 2
(-2100 1625);
DISPLAY 0.680851 (-2100 1625);
DISPLAY INVISIBLE (-2100 1625);
FORCEPROP 2 LASTPIN (-2200 1550) $PN 1
J 0
(-2190 1560);
DISPLAY 0.808511 (-2190 1560);
FORCEPROP 2 LASTPIN (-2350 1550) $PN 2
J 2
(-2360 1560);
DISPLAY 0.808511 (-2360 1560);
FORCEPROP 2 LAST VALUE DIFF BUS_0.22UF
J 2
(-2425 1550);
DISPLAY 0.553191 (-2425 1550);
FORCEPROP 1 LAST CDS_LMAN_SYM_OUTLINE -25,50,25,-50
J 2
(-2275 1550);
DISPLAY 0.468085 (-2275 1550);
PAINT GREEN (-2275 1550);
DISPLAY INVISIBLE (-2275 1550);
FORCEPROP 2 LAST CDS_LIB pure_quanta
J 2
(-2275 1550);
DISPLAY INVISIBLE (-2275 1550);
FORCEPROP 1 LAST PIN_NAMES_ROTATE TRUE
J 2
(-2275 1550);
DISPLAY 0.489362 (-2275 1550);
PAINT GREEN (-2275 1550);
DISPLAY INVISIBLE (-2275 1550);
FORCEPROP 2 LAST VOLTAGE 6.3V
J 2
(-2625 1600);
DISPLAY 0.553191 (-2625 1600);
DISPLAY INVISIBLE (-2625 1600);
FORCEPROP 1 LAST MATERIAL X6S
J 2
(-2266 1629);
DISPLAY 0.574468 (-2266 1629);
PAINT GREEN (-2266 1629);
DISPLAY INVISIBLE (-2266 1629);
FORCEPROP 2 LAST PACK_TYPE C0201
J 2
(-2450 1600);
DISPLAY 0.553191 (-2450 1600);
DISPLAY INVISIBLE (-2450 1600);
FORCEPROP 2 LAST TOLERANCE 20%
J 2
(-2350 1600);
DISPLAY 0.553191 (-2350 1600);
DISPLAY INVISIBLE (-2350 1600);
FORCEPROP 1 LAST PATH I34
J 2
(-2275 1550);
DISPLAY 0.723404 (-2275 1550);
DISPLAY INVISIBLE (-2275 1550);
FORCEPROP 1 LAST PART_NUMBER SP_CH4221MEE01
J 2
(-2391 1638);
DISPLAY 0.574468 (-2391 1638);
PAINT GREEN (-2391 1638);
DISPLAY INVISIBLE (-2391 1638);
FORCEPROP 1 LAST LOCATION C6569
J 0
(-2025 1625);
DISPLAY 1.021277 (-2025 1625);
DISPLAY INVISIBLE (-2025 1625);
FORCEADD TAP..1
(-1725 950);
FORCEPROP 3 LASTPIN (-1775 950) SIG_NAME P5E_CPU0_P2_TX_BUF_C_DP<5>
J 0
(-1765 960);
DISPLAY 0.659574 (-1765 960);
PAINT MONO (-1765 960);
DISPLAY INVISIBLE (-1765 960);
FORCEPROP 1 LASTPIN (-1775 950) BN 5
J 0
(-1787 958);
DISPLAY 0.680851 (-1787 958);
PAINT GREEN (-1787 958);
FORCEPROP 2 LAST CDS_LIB standard
J 0
(-1725 950);
DISPLAY INVISIBLE (-1725 950);
FORCEPROP 1 LAST BODY_TYPE PLUMBING
J 0
(-1725 1000);
DISPLAY 0.872340 (-1725 1000);
PAINT GREEN (-1725 1000);
DISPLAY INVISIBLE (-1725 1000);
FORCEPROP 1 LAST HDL_TAP TRUE
J 0
(-1400 825);
DISPLAY 0.872340 (-1400 825);
DISPLAY INVISIBLE (-1400 825);
FORCEPROP 1 LAST PATH I35
J 0
(-1727 950);
DISPLAY 0.872340 (-1727 950);
PAINT GREEN (-1727 950);
DISPLAY INVISIBLE (-1727 950);
FORCEADD TAP..1
(-1525 900);
FORCEPROP 3 LASTPIN (-1575 900) SIG_NAME P5E_CPU0_P2_TX_BUF_C_DN<5>
J 0
(-1565 910);
DISPLAY 0.659574 (-1565 910);
PAINT MONO (-1565 910);
DISPLAY INVISIBLE (-1565 910);
FORCEPROP 1 LASTPIN (-1575 900) BN 5
J 0
(-1587 908);
DISPLAY 0.680851 (-1587 908);
PAINT GREEN (-1587 908);
FORCEPROP 2 LAST CDS_LIB standard
J 0
(-1525 900);
DISPLAY INVISIBLE (-1525 900);
FORCEPROP 1 LAST BODY_TYPE PLUMBING
J 0
(-1525 950);
DISPLAY 0.872340 (-1525 950);
PAINT GREEN (-1525 950);
DISPLAY INVISIBLE (-1525 950);
FORCEPROP 1 LAST HDL_TAP TRUE
J 0
(-1200 775);
DISPLAY 0.872340 (-1200 775);
DISPLAY INVISIBLE (-1200 775);
FORCEPROP 1 LAST PATH I36
J 0
(-1527 900);
DISPLAY 0.872340 (-1527 900);
PAINT GREEN (-1527 900);
DISPLAY INVISIBLE (-1527 900);
FORCEADD TAP..1
(-1725 1150);
FORCEPROP 3 LASTPIN (-1775 1150) SIG_NAME P5E_CPU0_P2_TX_BUF_C_DP<4>
J 0
(-1765 1160);
DISPLAY 0.659574 (-1765 1160);
PAINT MONO (-1765 1160);
DISPLAY INVISIBLE (-1765 1160);
FORCEPROP 1 LASTPIN (-1775 1150) BN 4
J 0
(-1787 1158);
DISPLAY 0.680851 (-1787 1158);
PAINT GREEN (-1787 1158);
FORCEPROP 2 LAST CDS_LIB standard
J 0
(-1725 1150);
DISPLAY INVISIBLE (-1725 1150);
FORCEPROP 1 LAST BODY_TYPE PLUMBING
J 0
(-1725 1200);
DISPLAY 0.872340 (-1725 1200);
PAINT GREEN (-1725 1200);
DISPLAY INVISIBLE (-1725 1200);
FORCEPROP 1 LAST HDL_TAP TRUE
J 0
(-1400 1025);
DISPLAY 0.872340 (-1400 1025);
DISPLAY INVISIBLE (-1400 1025);
FORCEPROP 1 LAST PATH I37
J 0
(-1727 1150);
DISPLAY 0.872340 (-1727 1150);
PAINT GREEN (-1727 1150);
DISPLAY INVISIBLE (-1727 1150);
FORCEADD TAP..1
(-1525 1100);
FORCEPROP 3 LASTPIN (-1575 1100) SIG_NAME P5E_CPU0_P2_TX_BUF_C_DN<4>
J 0
(-1565 1110);
DISPLAY 0.659574 (-1565 1110);
PAINT MONO (-1565 1110);
DISPLAY INVISIBLE (-1565 1110);
FORCEPROP 1 LASTPIN (-1575 1100) BN 4
J 0
(-1587 1108);
DISPLAY 0.680851 (-1587 1108);
PAINT GREEN (-1587 1108);
FORCEPROP 2 LAST CDS_LIB standard
J 0
(-1525 1100);
DISPLAY INVISIBLE (-1525 1100);
FORCEPROP 1 LAST BODY_TYPE PLUMBING
J 0
(-1525 1150);
DISPLAY 0.872340 (-1525 1150);
PAINT GREEN (-1525 1150);
DISPLAY INVISIBLE (-1525 1150);
FORCEPROP 1 LAST HDL_TAP TRUE
J 0
(-1200 975);
DISPLAY 0.872340 (-1200 975);
DISPLAY INVISIBLE (-1200 975);
FORCEPROP 1 LAST PATH I38
J 0
(-1527 1100);
DISPLAY 0.872340 (-1527 1100);
PAINT GREEN (-1527 1100);
DISPLAY INVISIBLE (-1527 1100);
FORCEADD TAP..1
(-1725 1350);
FORCEPROP 3 LASTPIN (-1775 1350) SIG_NAME P5E_CPU0_P2_TX_BUF_C_DP<3>
J 0
(-1765 1360);
DISPLAY 0.659574 (-1765 1360);
PAINT MONO (-1765 1360);
DISPLAY INVISIBLE (-1765 1360);
FORCEPROP 1 LASTPIN (-1775 1350) BN 3
J 0
(-1787 1358);
DISPLAY 0.680851 (-1787 1358);
PAINT GREEN (-1787 1358);
FORCEPROP 2 LAST CDS_LIB standard
J 0
(-1725 1350);
DISPLAY INVISIBLE (-1725 1350);
FORCEPROP 1 LAST BODY_TYPE PLUMBING
J 0
(-1725 1400);
DISPLAY 0.872340 (-1725 1400);
PAINT GREEN (-1725 1400);
DISPLAY INVISIBLE (-1725 1400);
FORCEPROP 1 LAST HDL_TAP TRUE
J 0
(-1400 1225);
DISPLAY 0.872340 (-1400 1225);
DISPLAY INVISIBLE (-1400 1225);
FORCEPROP 1 LAST PATH I39
J 0
(-1727 1350);
DISPLAY 0.872340 (-1727 1350);
PAINT GREEN (-1727 1350);
DISPLAY INVISIBLE (-1727 1350);
FORCEADD TAP..1
R 2
(-3250 700);
FORCEPROP 3 LASTPIN (-3200 700) SIG_NAME P5E_CPU0_P2_TX_BUF_DN<6>
J 0
(-3190 710);
DISPLAY 0.659574 (-3190 710);
PAINT MONO (-3190 710);
DISPLAY INVISIBLE (-3190 710);
FORCEPROP 1 LASTPIN (-3200 700) BN 6
J 2
(-3188 708);
DISPLAY 0.680851 (-3188 708);
PAINT GREEN (-3188 708);
FORCEPROP 2 LAST CDS_LIB standard
J 0
(-3250 700);
DISPLAY INVISIBLE (-3250 700);
FORCEPROP 1 LAST BODY_TYPE PLUMBING
J 2
(-3250 750);
DISPLAY 0.872340 (-3250 750);
PAINT GREEN (-3250 750);
DISPLAY INVISIBLE (-3250 750);
FORCEPROP 1 LAST HDL_TAP TRUE
J 2
(-3575 575);
DISPLAY 0.872340 (-3575 575);
DISPLAY INVISIBLE (-3575 575);
FORCEPROP 1 LAST PATH I4
J 2
(-3248 700);
DISPLAY 0.872340 (-3248 700);
PAINT GREEN (-3248 700);
DISPLAY INVISIBLE (-3248 700);
FORCEADD TAP..1
(-1525 1500);
FORCEPROP 3 LASTPIN (-1575 1500) SIG_NAME P5E_CPU0_P2_TX_BUF_C_DN<2>
J 0
(-1565 1510);
DISPLAY 0.659574 (-1565 1510);
PAINT MONO (-1565 1510);
DISPLAY INVISIBLE (-1565 1510);
FORCEPROP 1 LASTPIN (-1575 1500) BN 2
J 0
(-1587 1508);
DISPLAY 0.680851 (-1587 1508);
PAINT GREEN (-1587 1508);
FORCEPROP 2 LAST CDS_LIB standard
J 0
(-1525 1500);
DISPLAY INVISIBLE (-1525 1500);
FORCEPROP 1 LAST BODY_TYPE PLUMBING
J 0
(-1525 1550);
DISPLAY 0.872340 (-1525 1550);
PAINT GREEN (-1525 1550);
DISPLAY INVISIBLE (-1525 1550);
FORCEPROP 1 LAST HDL_TAP TRUE
J 0
(-1200 1375);
DISPLAY 0.872340 (-1200 1375);
DISPLAY INVISIBLE (-1200 1375);
FORCEPROP 1 LAST PATH I40
J 0
(-1527 1500);
DISPLAY 0.872340 (-1527 1500);
PAINT GREEN (-1527 1500);
DISPLAY INVISIBLE (-1527 1500);
FORCEADD TAP..1
(-1525 1300);
FORCEPROP 3 LASTPIN (-1575 1300) SIG_NAME P5E_CPU0_P2_TX_BUF_C_DN<3>
J 0
(-1565 1310);
DISPLAY 0.659574 (-1565 1310);
PAINT MONO (-1565 1310);
DISPLAY INVISIBLE (-1565 1310);
FORCEPROP 1 LASTPIN (-1575 1300) BN 3
J 0
(-1587 1308);
DISPLAY 0.680851 (-1587 1308);
PAINT GREEN (-1587 1308);
FORCEPROP 2 LAST CDS_LIB standard
J 0
(-1525 1300);
DISPLAY INVISIBLE (-1525 1300);
FORCEPROP 1 LAST BODY_TYPE PLUMBING
J 0
(-1525 1350);
DISPLAY 0.872340 (-1525 1350);
PAINT GREEN (-1525 1350);
DISPLAY INVISIBLE (-1525 1350);
FORCEPROP 1 LAST HDL_TAP TRUE
J 0
(-1200 1175);
DISPLAY 0.872340 (-1200 1175);
DISPLAY INVISIBLE (-1200 1175);
FORCEPROP 1 LAST PATH I41
J 0
(-1527 1300);
DISPLAY 0.872340 (-1527 1300);
PAINT GREEN (-1527 1300);
DISPLAY INVISIBLE (-1527 1300);
FORCEADD TAP..1
(-1725 1550);
FORCEPROP 3 LASTPIN (-1775 1550) SIG_NAME P5E_CPU0_P2_TX_BUF_C_DP<2>
J 0
(-1765 1560);
DISPLAY 0.659574 (-1765 1560);
PAINT MONO (-1765 1560);
DISPLAY INVISIBLE (-1765 1560);
FORCEPROP 1 LASTPIN (-1775 1550) BN 2
J 0
(-1787 1558);
DISPLAY 0.680851 (-1787 1558);
PAINT GREEN (-1787 1558);
FORCEPROP 2 LAST CDS_LIB standard
J 0
(-1725 1550);
DISPLAY INVISIBLE (-1725 1550);
FORCEPROP 1 LAST BODY_TYPE PLUMBING
J 0
(-1725 1600);
DISPLAY 0.872340 (-1725 1600);
PAINT GREEN (-1725 1600);
DISPLAY INVISIBLE (-1725 1600);
FORCEPROP 1 LAST HDL_TAP TRUE
J 0
(-1400 1425);
DISPLAY 0.872340 (-1400 1425);
DISPLAY INVISIBLE (-1400 1425);
FORCEPROP 1 LAST PATH I42
J 0
(-1727 1550);
DISPLAY 0.872340 (-1727 1550);
PAINT GREEN (-1727 1550);
DISPLAY INVISIBLE (-1727 1550);
FORCEADD TAP..1
(-1725 1750);
FORCEPROP 3 LASTPIN (-1775 1750) SIG_NAME P5E_CPU0_P2_TX_BUF_C_DP<1>
J 0
(-1765 1760);
DISPLAY 0.659574 (-1765 1760);
PAINT MONO (-1765 1760);
DISPLAY INVISIBLE (-1765 1760);
FORCEPROP 1 LASTPIN (-1775 1750) BN 1
J 0
(-1787 1758);
DISPLAY 0.680851 (-1787 1758);
PAINT GREEN (-1787 1758);
FORCEPROP 2 LAST CDS_LIB standard
J 0
(-1725 1750);
DISPLAY INVISIBLE (-1725 1750);
FORCEPROP 1 LAST BODY_TYPE PLUMBING
J 0
(-1725 1800);
DISPLAY 0.872340 (-1725 1800);
PAINT GREEN (-1725 1800);
DISPLAY INVISIBLE (-1725 1800);
FORCEPROP 1 LAST HDL_TAP TRUE
J 0
(-1400 1625);
DISPLAY 0.872340 (-1400 1625);
DISPLAY INVISIBLE (-1400 1625);
FORCEPROP 1 LAST PATH I43
J 0
(-1727 1750);
DISPLAY 0.872340 (-1727 1750);
PAINT GREEN (-1727 1750);
DISPLAY INVISIBLE (-1727 1750);
FORCEADD TAP..1
(-1525 1700);
FORCEPROP 3 LASTPIN (-1575 1700) SIG_NAME P5E_CPU0_P2_TX_BUF_C_DN<1>
J 0
(-1565 1710);
DISPLAY 0.659574 (-1565 1710);
PAINT MONO (-1565 1710);
DISPLAY INVISIBLE (-1565 1710);
FORCEPROP 1 LASTPIN (-1575 1700) BN 1
J 0
(-1587 1708);
DISPLAY 0.680851 (-1587 1708);
PAINT GREEN (-1587 1708);
FORCEPROP 2 LAST CDS_LIB standard
J 0
(-1525 1700);
DISPLAY INVISIBLE (-1525 1700);
FORCEPROP 1 LAST BODY_TYPE PLUMBING
J 0
(-1525 1750);
DISPLAY 0.872340 (-1525 1750);
PAINT GREEN (-1525 1750);
DISPLAY INVISIBLE (-1525 1750);
FORCEPROP 1 LAST HDL_TAP TRUE
J 0
(-1200 1575);
DISPLAY 0.872340 (-1200 1575);
DISPLAY INVISIBLE (-1200 1575);
FORCEPROP 1 LAST PATH I44
J 0
(-1527 1700);
DISPLAY 0.872340 (-1527 1700);
PAINT GREEN (-1527 1700);
DISPLAY INVISIBLE (-1527 1700);
FORCEADD TAP..1
R 2
(-3250 1900);
FORCEPROP 3 LASTPIN (-3200 1900) SIG_NAME P5E_CPU0_P2_TX_BUF_DN<0>
J 0
(-3190 1910);
DISPLAY 0.659574 (-3190 1910);
PAINT MONO (-3190 1910);
DISPLAY INVISIBLE (-3190 1910);
FORCEPROP 1 LASTPIN (-3200 1900) BN 0
J 2
(-3188 1908);
DISPLAY 0.680851 (-3188 1908);
PAINT GREEN (-3188 1908);
FORCEPROP 2 LAST CDS_LIB standard
J 0
(-3250 1900);
DISPLAY INVISIBLE (-3250 1900);
FORCEPROP 1 LAST BODY_TYPE PLUMBING
J 2
(-3250 1950);
DISPLAY 0.872340 (-3250 1950);
PAINT GREEN (-3250 1950);
DISPLAY INVISIBLE (-3250 1950);
FORCEPROP 1 LAST HDL_TAP TRUE
J 2
(-3575 1775);
DISPLAY 0.872340 (-3575 1775);
DISPLAY INVISIBLE (-3575 1775);
FORCEPROP 1 LAST PATH I45
J 2
(-3248 1900);
DISPLAY 0.872340 (-3248 1900);
PAINT GREEN (-3248 1900);
DISPLAY INVISIBLE (-3248 1900);
FORCEADD TAP..1
R 2
(-3000 1950);
FORCEPROP 3 LASTPIN (-2950 1950) SIG_NAME P5E_CPU0_P2_TX_BUF_DP<0>
J 0
(-2940 1960);
DISPLAY 0.659574 (-2940 1960);
PAINT MONO (-2940 1960);
DISPLAY INVISIBLE (-2940 1960);
FORCEPROP 1 LASTPIN (-2950 1950) BN 0
J 2
(-2938 1958);
DISPLAY 0.680851 (-2938 1958);
PAINT GREEN (-2938 1958);
FORCEPROP 2 LAST CDS_LIB standard
J 0
(-3000 1950);
DISPLAY INVISIBLE (-3000 1950);
FORCEPROP 1 LAST BODY_TYPE PLUMBING
J 2
(-3000 2000);
DISPLAY 0.872340 (-3000 2000);
PAINT GREEN (-3000 2000);
DISPLAY INVISIBLE (-3000 2000);
FORCEPROP 1 LAST HDL_TAP TRUE
J 2
(-3325 1825);
DISPLAY 0.872340 (-3325 1825);
DISPLAY INVISIBLE (-3325 1825);
FORCEPROP 1 LAST PATH I46
J 2
(-2998 1950);
DISPLAY 0.872340 (-2998 1950);
PAINT GREEN (-2998 1950);
DISPLAY INVISIBLE (-2998 1950);
FORCEADD PT5161LRS..10
(-7825 4375);
FORCEPROP 1 LAST LOCATION U6012
J 0
(-8175 6000);
DISPLAY 0.723404 (-8175 6000);
PAINT GREEN (-8175 6000);
FORCEPROP 0 LAST $SEC 10
J 0
(-8175 6150);
DISPLAY 0.680851 (-8175 6150);
PAINT MONO (-8175 6150);
DISPLAY INVISIBLE (-8175 6150);
FORCEPROP 0 LAST CDS_SEC 10
J 0
(-8175 6150);
DISPLAY 0.680851 (-8175 6150);
DISPLAY INVISIBLE (-8175 6150);
FORCEPROP 0 LASTPIN (-7375 5525) $PN P10
J 0
(-7365 5535);
DISPLAY 0.680851 (-7365 5535);
PAINT MONO (-7365 5535);
FORCEPROP 0 LASTPIN (-7375 5175) $PN AA10
J 0
(-7365 5185);
DISPLAY 0.680851 (-7365 5185);
PAINT MONO (-7365 5185);
FORCEPROP 0 LASTPIN (-7375 4825) $PN AH10
J 0
(-7365 4835);
DISPLAY 0.680851 (-7365 4835);
PAINT MONO (-7365 4835);
FORCEPROP 0 LASTPIN (-7375 4475) $PN AR10
J 0
(-7365 4485);
DISPLAY 0.680851 (-7365 4485);
PAINT MONO (-7365 4485);
FORCEPROP 0 LASTPIN (-7375 4125) $PN BB10
J 0
(-7365 4135);
DISPLAY 0.680851 (-7365 4135);
PAINT MONO (-7365 4135);
FORCEPROP 0 LASTPIN (-7375 3775) $PN BJ10
J 0
(-7365 3785);
DISPLAY 0.680851 (-7365 3785);
PAINT MONO (-7365 3785);
FORCEPROP 0 LASTPIN (-7375 3425) $PN BT10
J 0
(-7365 3435);
DISPLAY 0.680851 (-7365 3435);
PAINT MONO (-7365 3435);
FORCEPROP 0 LASTPIN (-7375 3075) $PN CC10
J 0
(-7365 3085);
DISPLAY 0.680851 (-7365 3085);
PAINT MONO (-7365 3085);
FORCEPROP 0 LASTPIN (-7375 5625) $PN M7
J 0
(-7365 5635);
DISPLAY 0.680851 (-7365 5635);
PAINT MONO (-7365 5635);
FORCEPROP 0 LASTPIN (-7375 5275) $PN W7
J 0
(-7365 5285);
DISPLAY 0.680851 (-7365 5285);
PAINT MONO (-7365 5285);
FORCEPROP 0 LASTPIN (-7375 4925) $PN AF7
J 0
(-7365 4935);
DISPLAY 0.680851 (-7365 4935);
PAINT MONO (-7365 4935);
FORCEPROP 0 LASTPIN (-7375 4575) $PN AN7
J 0
(-7365 4585);
DISPLAY 0.680851 (-7365 4585);
PAINT MONO (-7365 4585);
FORCEPROP 0 LASTPIN (-7375 4225) $PN AY7
J 0
(-7365 4235);
DISPLAY 0.680851 (-7365 4235);
PAINT MONO (-7365 4235);
FORCEPROP 0 LASTPIN (-7375 3875) $PN BG7
J 0
(-7365 3885);
DISPLAY 0.680851 (-7365 3885);
PAINT MONO (-7365 3885);
FORCEPROP 0 LASTPIN (-7375 3525) $PN BP7
J 0
(-7365 3535);
DISPLAY 0.680851 (-7365 3535);
PAINT MONO (-7365 3535);
FORCEPROP 0 LASTPIN (-7375 3175) $PN CA7
J 0
(-7365 3185);
DISPLAY 0.680851 (-7365 3185);
PAINT MONO (-7365 3185);
FORCEPROP 1 LAST MATERIAL IC
J 0
(-8175 5850);
DISPLAY 0.723404 (-8175 5850);
PAINT GREEN (-8175 5850);
FORCEPROP 2 LAST PART_TYPE SMLF
J 0
(-8175 6100);
DISPLAY 0.680851 (-8175 6100);
FORCEPROP 2 LAST VALUE PT5161LRS
J 0
(-8175 6050);
DISPLAY 0.680851 (-8175 6050);
FORCEPROP 1 LAST NEEDS_NO_SIZE TRUE
J 0
(-7825 4375);
DISPLAY 0.723404 (-7825 4375);
PAINT GREEN (-7825 4375);
DISPLAY INVISIBLE (-7825 4375);
FORCEPROP 1 LAST CDS_LMAN_SYM_OUTLINE -350,1450,300,-1400
J 0
(-7825 4375);
DISPLAY 0.468085 (-7825 4375);
PAINT GREEN (-7825 4375);
DISPLAY INVISIBLE (-7825 4375);
FORCEPROP 2 LAST CDS_LIB pure_quanta
J 0
(-7825 4375);
DISPLAY INVISIBLE (-7825 4375);
FORCEPROP 1 LAST PATH I47
J 0
(-7825 4375);
DISPLAY 0.723404 (-7825 4375);
PAINT GREEN (-7825 4375);
DISPLAY INVISIBLE (-7825 4375);
FORCEPROP 1 LAST PART_NUMBER AJ051610U03
J 0
(-8175 5925);
DISPLAY 0.723404 (-8175 5925);
PAINT GREEN (-8175 5925);
DISPLAY INVISIBLE (-8175 5925);
FORCEADD Q_CAP_DIFFBUS..2
R 2
(-2275 1900);
FORCEPROP 1 LAST LOCATION C6566
J 2
(-1975 1900);
DISPLAY 0.723404 (-1975 1900);
PAINT GREEN (-1975 1900);
FORCEPROP 2 LAST $SEC 1
J 2
(-2100 1975);
DISPLAY 0.680851 (-2100 1975);
PAINT MONO (-2100 1975);
DISPLAY INVISIBLE (-2100 1975);
FORCEPROP 2 LAST CDS_SEC 1
J 2
(-2100 1975);
DISPLAY 0.680851 (-2100 1975);
DISPLAY INVISIBLE (-2100 1975);
FORCEPROP 2 LASTPIN (-2200 1900) $PN 1
J 0
(-2190 1910);
DISPLAY 0.808511 (-2190 1910);
FORCEPROP 2 LASTPIN (-2350 1900) $PN 2
J 2
(-2360 1910);
DISPLAY 0.808511 (-2360 1910);
FORCEPROP 2 LAST VALUE DIFF BUS_0.22UF
J 2
(-2425 1900);
DISPLAY 0.553191 (-2425 1900);
FORCEPROP 1 LAST CDS_LMAN_SYM_OUTLINE -25,50,25,-50
J 2
(-2275 1900);
DISPLAY 0.468085 (-2275 1900);
PAINT GREEN (-2275 1900);
DISPLAY INVISIBLE (-2275 1900);
FORCEPROP 2 LAST CDS_LIB pure_quanta
J 2
(-2275 1900);
DISPLAY INVISIBLE (-2275 1900);
FORCEPROP 1 LAST PIN_NAMES_ROTATE TRUE
J 2
(-2275 1900);
DISPLAY 0.489362 (-2275 1900);
PAINT GREEN (-2275 1900);
DISPLAY INVISIBLE (-2275 1900);
FORCEPROP 2 LAST VOLTAGE 6.3V
J 2
(-2625 1950);
DISPLAY 0.553191 (-2625 1950);
DISPLAY INVISIBLE (-2625 1950);
FORCEPROP 1 LAST MATERIAL X6S
J 2
(-2266 1979);
DISPLAY 0.574468 (-2266 1979);
PAINT GREEN (-2266 1979);
DISPLAY INVISIBLE (-2266 1979);
FORCEPROP 2 LAST PACK_TYPE C0201
J 2
(-2450 1950);
DISPLAY 0.553191 (-2450 1950);
DISPLAY INVISIBLE (-2450 1950);
FORCEPROP 2 LAST TOLERANCE 20%
J 2
(-2350 1950);
DISPLAY 0.553191 (-2350 1950);
DISPLAY INVISIBLE (-2350 1950);
FORCEPROP 1 LAST PATH I48
J 2
(-2275 1900);
DISPLAY 0.723404 (-2275 1900);
DISPLAY INVISIBLE (-2275 1900);
FORCEPROP 1 LAST PART_NUMBER SP_CH4221MEE01
J 2
(-2391 1988);
DISPLAY 0.574468 (-2391 1988);
PAINT GREEN (-2391 1988);
DISPLAY INVISIBLE (-2391 1988);
FORCEPROP 1 LAST LOCATION C6566
J 0
(-2025 1975);
DISPLAY 1.021277 (-2025 1975);
DISPLAY INVISIBLE (-2025 1975);
FORCEADD Q_CAP_DIFFBUS..2
R 2
(-2275 1950);
FORCEPROP 1 LAST LOCATION C6565
J 2
(-1975 1950);
DISPLAY 0.723404 (-1975 1950);
PAINT GREEN (-1975 1950);
FORCEPROP 2 LAST $SEC 1
J 2
(-2100 2025);
DISPLAY 0.680851 (-2100 2025);
PAINT MONO (-2100 2025);
DISPLAY INVISIBLE (-2100 2025);
FORCEPROP 2 LAST CDS_SEC 1
J 2
(-2100 2025);
DISPLAY 0.680851 (-2100 2025);
DISPLAY INVISIBLE (-2100 2025);
FORCEPROP 2 LASTPIN (-2200 1950) $PN 1
J 0
(-2190 1960);
DISPLAY 0.808511 (-2190 1960);
FORCEPROP 2 LASTPIN (-2350 1950) $PN 2
J 2
(-2360 1960);
DISPLAY 0.808511 (-2360 1960);
FORCEPROP 2 LAST PACK_TYPE C0201
J 2
(-2325 2100);
DISPLAY 0.553191 (-2325 2100);
PAINT GREEN (-2325 2100);
FORCEPROP 1 LAST MATERIAL X6S
J 2
(-2366 2154);
DISPLAY 0.574468 (-2366 2154);
PAINT GREEN (-2366 2154);
FORCEPROP 2 LAST TOLERANCE 20%
J 2
(-2225 2100);
DISPLAY 0.553191 (-2225 2100);
PAINT GREEN (-2225 2100);
FORCEPROP 2 LAST VOLTAGE 6.3V
J 2
(-2100 2100);
DISPLAY 0.553191 (-2100 2100);
PAINT GREEN (-2100 2100);
FORCEPROP 2 LAST VALUE DIFF BUS_0.22UF
J 2
(-2425 1950);
DISPLAY 0.553191 (-2425 1950);
FORCEPROP 2 LAST CDS_LIB pure_quanta
J 2
(-2275 1950);
DISPLAY INVISIBLE (-2275 1950);
FORCEPROP 1 LAST CDS_LMAN_SYM_OUTLINE -25,50,25,-50
J 2
(-2275 1950);
DISPLAY 0.468085 (-2275 1950);
PAINT GREEN (-2275 1950);
DISPLAY INVISIBLE (-2275 1950);
FORCEPROP 1 LAST PIN_NAMES_ROTATE TRUE
J 2
(-2275 1950);
DISPLAY 0.489362 (-2275 1950);
PAINT GREEN (-2275 1950);
DISPLAY INVISIBLE (-2275 1950);
FORCEPROP 1 LAST PATH I49
J 2
(-2275 1950);
DISPLAY 0.723404 (-2275 1950);
DISPLAY INVISIBLE (-2275 1950);
FORCEPROP 1 LAST PART_NUMBER SP_CH4221MEE01
J 2
(-2091 2038);
DISPLAY 0.574468 (-2091 2038);
PAINT GREEN (-2091 2038);
DISPLAY INVISIBLE (-2091 2038);
FORCEPROP 1 LAST LOCATION C6565
J 0
(-2025 2025);
DISPLAY 1.021277 (-2025 2025);
DISPLAY INVISIBLE (-2025 2025);
FORCEADD TAP..1
R 2
(-3000 750);
FORCEPROP 3 LASTPIN (-2950 750) SIG_NAME P5E_CPU0_P2_TX_BUF_DP<6>
J 0
(-2940 760);
DISPLAY 0.659574 (-2940 760);
PAINT MONO (-2940 760);
DISPLAY INVISIBLE (-2940 760);
FORCEPROP 1 LASTPIN (-2950 750) BN 6
J 2
(-2938 758);
DISPLAY 0.680851 (-2938 758);
PAINT GREEN (-2938 758);
FORCEPROP 2 LAST CDS_LIB standard
J 0
(-3000 750);
DISPLAY INVISIBLE (-3000 750);
FORCEPROP 1 LAST BODY_TYPE PLUMBING
J 2
(-3000 800);
DISPLAY 0.872340 (-3000 800);
PAINT GREEN (-3000 800);
DISPLAY INVISIBLE (-3000 800);
FORCEPROP 1 LAST HDL_TAP TRUE
J 2
(-3325 625);
DISPLAY 0.872340 (-3325 625);
DISPLAY INVISIBLE (-3325 625);
FORCEPROP 1 LAST PATH I5
J 2
(-2998 750);
DISPLAY 0.872340 (-2998 750);
PAINT GREEN (-2998 750);
DISPLAY INVISIBLE (-2998 750);
FORCEADD TAP..1
(-1725 1950);
FORCEPROP 3 LASTPIN (-1775 1950) SIG_NAME P5E_CPU0_P2_TX_BUF_C_DP<0>
J 0
(-1765 1960);
DISPLAY 0.659574 (-1765 1960);
PAINT MONO (-1765 1960);
DISPLAY INVISIBLE (-1765 1960);
FORCEPROP 1 LASTPIN (-1775 1950) BN 0
J 0
(-1787 1958);
DISPLAY 0.680851 (-1787 1958);
PAINT GREEN (-1787 1958);
FORCEPROP 2 LAST CDS_LIB standard
J 0
(-1725 1950);
DISPLAY INVISIBLE (-1725 1950);
FORCEPROP 1 LAST BODY_TYPE PLUMBING
J 0
(-1725 2000);
DISPLAY 0.872340 (-1725 2000);
PAINT GREEN (-1725 2000);
DISPLAY INVISIBLE (-1725 2000);
FORCEPROP 1 LAST HDL_TAP TRUE
J 0
(-1400 1825);
DISPLAY 0.872340 (-1400 1825);
DISPLAY INVISIBLE (-1400 1825);
FORCEPROP 1 LAST PATH I50
J 0
(-1727 1950);
DISPLAY 0.872340 (-1727 1950);
PAINT GREEN (-1727 1950);
DISPLAY INVISIBLE (-1727 1950);
FORCEADD TAP..1
(-1525 1900);
FORCEPROP 3 LASTPIN (-1575 1900) SIG_NAME P5E_CPU0_P2_TX_BUF_C_DN<0>
J 0
(-1565 1910);
DISPLAY 0.659574 (-1565 1910);
PAINT MONO (-1565 1910);
DISPLAY INVISIBLE (-1565 1910);
FORCEPROP 1 LASTPIN (-1575 1900) BN 0
J 0
(-1587 1908);
DISPLAY 0.680851 (-1587 1908);
PAINT GREEN (-1587 1908);
FORCEPROP 2 LAST CDS_LIB standard
J 0
(-1525 1900);
DISPLAY INVISIBLE (-1525 1900);
FORCEPROP 1 LAST BODY_TYPE PLUMBING
J 0
(-1525 1950);
DISPLAY 0.872340 (-1525 1950);
PAINT GREEN (-1525 1950);
DISPLAY INVISIBLE (-1525 1950);
FORCEPROP 1 LAST HDL_TAP TRUE
J 0
(-1200 1775);
DISPLAY 0.872340 (-1200 1775);
DISPLAY INVISIBLE (-1200 1775);
FORCEPROP 1 LAST PATH I51
J 0
(-1527 1900);
DISPLAY 0.872340 (-1527 1900);
PAINT GREEN (-1527 1900);
DISPLAY INVISIBLE (-1527 1900);
FORCEADD TAP..1
(-7100 3175);
FORCEPROP 3 LASTPIN (-7150 3175) SIG_NAME P5E_CPU0_P2_TX_BUF_DP<8>
J 0
(-7140 3185);
DISPLAY 0.659574 (-7140 3185);
PAINT MONO (-7140 3185);
DISPLAY INVISIBLE (-7140 3185);
FORCEPROP 1 LASTPIN (-7150 3175) BN 8
J 0
(-7162 3183);
DISPLAY 0.680851 (-7162 3183);
PAINT GREEN (-7162 3183);
FORCEPROP 2 LAST CDS_LIB standard
J 0
(-7100 3175);
DISPLAY INVISIBLE (-7100 3175);
FORCEPROP 1 LAST BODY_TYPE PLUMBING
J 0
(-7100 3225);
DISPLAY 0.872340 (-7100 3225);
PAINT GREEN (-7100 3225);
DISPLAY INVISIBLE (-7100 3225);
FORCEPROP 1 LAST HDL_TAP TRUE
J 0
(-6775 3050);
DISPLAY 0.872340 (-6775 3050);
DISPLAY INVISIBLE (-6775 3050);
FORCEPROP 1 LAST PATH I52
J 0
(-7102 3175);
DISPLAY 0.872340 (-7102 3175);
PAINT GREEN (-7102 3175);
DISPLAY INVISIBLE (-7102 3175);
FORCEADD TAP..1
(-6900 3075);
FORCEPROP 3 LASTPIN (-6950 3075) SIG_NAME P5E_CPU0_P2_TX_BUF_DN<8>
J 0
(-6940 3085);
DISPLAY 0.659574 (-6940 3085);
PAINT MONO (-6940 3085);
DISPLAY INVISIBLE (-6940 3085);
FORCEPROP 1 LASTPIN (-6950 3075) BN 8
J 0
(-6962 3083);
DISPLAY 0.680851 (-6962 3083);
PAINT GREEN (-6962 3083);
FORCEPROP 2 LAST CDS_LIB standard
J 0
(-6900 3075);
DISPLAY INVISIBLE (-6900 3075);
FORCEPROP 1 LAST BODY_TYPE PLUMBING
J 0
(-6900 3125);
DISPLAY 0.872340 (-6900 3125);
PAINT GREEN (-6900 3125);
DISPLAY INVISIBLE (-6900 3125);
FORCEPROP 1 LAST HDL_TAP TRUE
J 0
(-6575 2950);
DISPLAY 0.872340 (-6575 2950);
DISPLAY INVISIBLE (-6575 2950);
FORCEPROP 1 LAST PATH I53
J 0
(-6902 3075);
DISPLAY 0.872340 (-6902 3075);
PAINT GREEN (-6902 3075);
DISPLAY INVISIBLE (-6902 3075);
FORCEADD TAP..1
(-7100 3525);
FORCEPROP 3 LASTPIN (-7150 3525) SIG_NAME P5E_CPU0_P2_TX_BUF_DP<9>
J 0
(-7140 3535);
DISPLAY 0.659574 (-7140 3535);
PAINT MONO (-7140 3535);
DISPLAY INVISIBLE (-7140 3535);
FORCEPROP 1 LASTPIN (-7150 3525) BN 9
J 0
(-7162 3533);
DISPLAY 0.680851 (-7162 3533);
PAINT GREEN (-7162 3533);
FORCEPROP 2 LAST CDS_LIB standard
J 0
(-7100 3525);
DISPLAY INVISIBLE (-7100 3525);
FORCEPROP 1 LAST BODY_TYPE PLUMBING
J 0
(-7100 3575);
DISPLAY 0.872340 (-7100 3575);
PAINT GREEN (-7100 3575);
DISPLAY INVISIBLE (-7100 3575);
FORCEPROP 1 LAST HDL_TAP TRUE
J 0
(-6775 3400);
DISPLAY 0.872340 (-6775 3400);
DISPLAY INVISIBLE (-6775 3400);
FORCEPROP 1 LAST PATH I54
J 0
(-7102 3525);
DISPLAY 0.872340 (-7102 3525);
PAINT GREEN (-7102 3525);
DISPLAY INVISIBLE (-7102 3525);
FORCEADD TAP..1
(-7100 3875);
FORCEPROP 3 LASTPIN (-7150 3875) SIG_NAME P5E_CPU0_P2_TX_BUF_DP<10>
J 0
(-7140 3885);
DISPLAY 0.659574 (-7140 3885);
PAINT MONO (-7140 3885);
DISPLAY INVISIBLE (-7140 3885);
FORCEPROP 1 LASTPIN (-7150 3875) BN 10
J 0
(-7162 3883);
DISPLAY 0.680851 (-7162 3883);
PAINT GREEN (-7162 3883);
FORCEPROP 2 LAST CDS_LIB standard
J 0
(-7100 3875);
DISPLAY INVISIBLE (-7100 3875);
FORCEPROP 1 LAST BODY_TYPE PLUMBING
J 0
(-7100 3925);
DISPLAY 0.872340 (-7100 3925);
PAINT GREEN (-7100 3925);
DISPLAY INVISIBLE (-7100 3925);
FORCEPROP 1 LAST HDL_TAP TRUE
J 0
(-6775 3750);
DISPLAY 0.872340 (-6775 3750);
DISPLAY INVISIBLE (-6775 3750);
FORCEPROP 1 LAST PATH I55
J 0
(-7102 3875);
DISPLAY 0.872340 (-7102 3875);
PAINT GREEN (-7102 3875);
DISPLAY INVISIBLE (-7102 3875);
FORCEADD TAP..1
(-6900 3425);
FORCEPROP 3 LASTPIN (-6950 3425) SIG_NAME P5E_CPU0_P2_TX_BUF_DN<9>
J 0
(-6940 3435);
DISPLAY 0.659574 (-6940 3435);
PAINT MONO (-6940 3435);
DISPLAY INVISIBLE (-6940 3435);
FORCEPROP 1 LASTPIN (-6950 3425) BN 9
J 0
(-6962 3433);
DISPLAY 0.680851 (-6962 3433);
PAINT GREEN (-6962 3433);
FORCEPROP 2 LAST CDS_LIB standard
J 0
(-6900 3425);
DISPLAY INVISIBLE (-6900 3425);
FORCEPROP 1 LAST BODY_TYPE PLUMBING
J 0
(-6900 3475);
DISPLAY 0.872340 (-6900 3475);
PAINT GREEN (-6900 3475);
DISPLAY INVISIBLE (-6900 3475);
FORCEPROP 1 LAST HDL_TAP TRUE
J 0
(-6575 3300);
DISPLAY 0.872340 (-6575 3300);
DISPLAY INVISIBLE (-6575 3300);
FORCEPROP 1 LAST PATH I56
J 0
(-6902 3425);
DISPLAY 0.872340 (-6902 3425);
PAINT GREEN (-6902 3425);
DISPLAY INVISIBLE (-6902 3425);
FORCEADD TAP..1
(-6900 3775);
FORCEPROP 3 LASTPIN (-6950 3775) SIG_NAME P5E_CPU0_P2_TX_BUF_DN<10>
J 0
(-6940 3785);
DISPLAY 0.659574 (-6940 3785);
PAINT MONO (-6940 3785);
DISPLAY INVISIBLE (-6940 3785);
FORCEPROP 1 LASTPIN (-6950 3775) BN 10
J 0
(-6962 3783);
DISPLAY 0.680851 (-6962 3783);
PAINT GREEN (-6962 3783);
FORCEPROP 2 LAST CDS_LIB standard
J 0
(-6900 3775);
DISPLAY INVISIBLE (-6900 3775);
FORCEPROP 1 LAST BODY_TYPE PLUMBING
J 0
(-6900 3825);
DISPLAY 0.872340 (-6900 3825);
PAINT GREEN (-6900 3825);
DISPLAY INVISIBLE (-6900 3825);
FORCEPROP 1 LAST HDL_TAP TRUE
J 0
(-6575 3650);
DISPLAY 0.872340 (-6575 3650);
DISPLAY INVISIBLE (-6575 3650);
FORCEPROP 1 LAST PATH I57
J 0
(-6902 3775);
DISPLAY 0.872340 (-6902 3775);
PAINT GREEN (-6902 3775);
DISPLAY INVISIBLE (-6902 3775);
FORCEADD OFFPAGE..2
(-525 1925);
FORCEPROP 2 LAST $XR0 116 
J 0
(-336 1925);
DISPLAY 0.638298 (-336 1925);
PAINT MONO (-336 1925);
FORCEPROP 2 LAST CDS_LIB standard
J 0
(-525 1925);
DISPLAY INVISIBLE (-525 1925);
FORCEPROP 1 LAST OFFPAGE TRUE
J 0
(-200 1800);
DISPLAY 0.872340 (-200 1800);
DISPLAY INVISIBLE (-200 1800);
FORCEPROP 1 LAST COMMENT_BODY TRUE
J 0
(-570 1830);
DISPLAY 0.872340 (-570 1830);
PAINT GREEN (-570 1830);
DISPLAY INVISIBLE (-570 1830);
FORCEPROP 2 LAST PATH I58
J 0
(-325 1975);
DISPLAY 0.680851 (-325 1975);
DISPLAY INVISIBLE (-325 1975);
FORCEADD OFFPAGE..2
(-525 1975);
FORCEPROP 2 LAST $XR0 116 
J 0
(-336 1975);
DISPLAY 0.638298 (-336 1975);
PAINT MONO (-336 1975);
FORCEPROP 2 LAST CDS_LIB standard
J 0
(-525 1975);
DISPLAY INVISIBLE (-525 1975);
FORCEPROP 1 LAST OFFPAGE TRUE
J 0
(-200 1850);
DISPLAY 0.872340 (-200 1850);
DISPLAY INVISIBLE (-200 1850);
FORCEPROP 1 LAST COMMENT_BODY TRUE
J 0
(-570 1880);
DISPLAY 0.872340 (-570 1880);
PAINT GREEN (-570 1880);
DISPLAY INVISIBLE (-570 1880);
FORCEPROP 2 LAST PATH I59
J 0
(-325 2025);
DISPLAY 0.680851 (-325 2025);
DISPLAY INVISIBLE (-325 2025);
FORCEADD TAP..1
R 2
(-3000 550);
FORCEPROP 3 LASTPIN (-2950 550) SIG_NAME P5E_CPU0_P2_TX_BUF_DP<7>
J 0
(-2940 560);
DISPLAY 0.659574 (-2940 560);
PAINT MONO (-2940 560);
DISPLAY INVISIBLE (-2940 560);
FORCEPROP 1 LASTPIN (-2950 550) BN 7
J 2
(-2938 558);
DISPLAY 0.680851 (-2938 558);
PAINT GREEN (-2938 558);
FORCEPROP 2 LAST CDS_LIB standard
J 0
(-3000 550);
DISPLAY INVISIBLE (-3000 550);
FORCEPROP 1 LAST BODY_TYPE PLUMBING
J 2
(-3000 600);
DISPLAY 0.872340 (-3000 600);
PAINT GREEN (-3000 600);
DISPLAY INVISIBLE (-3000 600);
FORCEPROP 1 LAST HDL_TAP TRUE
J 2
(-3325 425);
DISPLAY 0.872340 (-3325 425);
DISPLAY INVISIBLE (-3325 425);
FORCEPROP 1 LAST PATH I6
J 2
(-2998 550);
DISPLAY 0.872340 (-2998 550);
PAINT GREEN (-2998 550);
DISPLAY INVISIBLE (-2998 550);
FORCEADD OFFPAGE..1
(-9050 2000);
FORCEPROP 2 LAST $XR0 298 
J 0
(-9332 2000);
DISPLAY 0.638298 (-9332 2000);
PAINT MONO (-9332 2000);
FORCEPROP 2 LAST CDS_LIB standard
J 0
(-9050 2000);
DISPLAY INVISIBLE (-9050 2000);
FORCEPROP 1 LAST OFFPAGE TRUE
J 0
(-8725 1875);
DISPLAY 0.872340 (-8725 1875);
DISPLAY INVISIBLE (-8725 1875);
FORCEPROP 1 LAST COMMENT_BODY TRUE
J 0
(-8925 1900);
DISPLAY 0.872340 (-8925 1900);
PAINT GREEN (-8925 1900);
DISPLAY INVISIBLE (-8925 1900);
FORCEPROP 2 LAST PATH I60
J 0
(-9300 2050);
DISPLAY 0.680851 (-9300 2050);
DISPLAY INVISIBLE (-9300 2050);
FORCEADD OFFPAGE..1
(-9050 2050);
FORCEPROP 2 LAST $XR0 298 
J 0
(-9332 2050);
DISPLAY 0.638298 (-9332 2050);
PAINT MONO (-9332 2050);
FORCEPROP 2 LAST CDS_LIB standard
J 0
(-9050 2050);
DISPLAY INVISIBLE (-9050 2050);
FORCEPROP 1 LAST OFFPAGE TRUE
J 0
(-8725 1925);
DISPLAY 0.872340 (-8725 1925);
DISPLAY INVISIBLE (-8725 1925);
FORCEPROP 1 LAST COMMENT_BODY TRUE
J 0
(-8925 1950);
DISPLAY 0.872340 (-8925 1950);
PAINT GREEN (-8925 1950);
DISPLAY INVISIBLE (-8925 1950);
FORCEPROP 2 LAST PATH I61
J 0
(-9300 2100);
DISPLAY 0.680851 (-9300 2100);
DISPLAY INVISIBLE (-9300 2100);
FORCEADD TAP..1
(-7100 4225);
FORCEPROP 3 LASTPIN (-7150 4225) SIG_NAME P5E_CPU0_P2_TX_BUF_DP<11>
J 0
(-7140 4235);
DISPLAY 0.659574 (-7140 4235);
PAINT MONO (-7140 4235);
DISPLAY INVISIBLE (-7140 4235);
FORCEPROP 1 LASTPIN (-7150 4225) BN 11
J 0
(-7162 4233);
DISPLAY 0.680851 (-7162 4233);
PAINT GREEN (-7162 4233);
FORCEPROP 2 LAST CDS_LIB standard
J 0
(-7100 4225);
DISPLAY INVISIBLE (-7100 4225);
FORCEPROP 1 LAST BODY_TYPE PLUMBING
J 0
(-7100 4275);
DISPLAY 0.872340 (-7100 4275);
PAINT GREEN (-7100 4275);
DISPLAY INVISIBLE (-7100 4275);
FORCEPROP 1 LAST HDL_TAP TRUE
J 0
(-6775 4100);
DISPLAY 0.872340 (-6775 4100);
DISPLAY INVISIBLE (-6775 4100);
FORCEPROP 1 LAST PATH I62
J 0
(-7102 4225);
DISPLAY 0.872340 (-7102 4225);
PAINT GREEN (-7102 4225);
DISPLAY INVISIBLE (-7102 4225);
FORCEADD TAP..1
(-6900 4125);
FORCEPROP 3 LASTPIN (-6950 4125) SIG_NAME P5E_CPU0_P2_TX_BUF_DN<11>
J 0
(-6940 4135);
DISPLAY 0.659574 (-6940 4135);
PAINT MONO (-6940 4135);
DISPLAY INVISIBLE (-6940 4135);
FORCEPROP 1 LASTPIN (-6950 4125) BN 11
J 0
(-6962 4133);
DISPLAY 0.680851 (-6962 4133);
PAINT GREEN (-6962 4133);
FORCEPROP 2 LAST CDS_LIB standard
J 0
(-6900 4125);
DISPLAY INVISIBLE (-6900 4125);
FORCEPROP 1 LAST BODY_TYPE PLUMBING
J 0
(-6900 4175);
DISPLAY 0.872340 (-6900 4175);
PAINT GREEN (-6900 4175);
DISPLAY INVISIBLE (-6900 4175);
FORCEPROP 1 LAST HDL_TAP TRUE
J 0
(-6575 4000);
DISPLAY 0.872340 (-6575 4000);
DISPLAY INVISIBLE (-6575 4000);
FORCEPROP 1 LAST PATH I63
J 0
(-6902 4125);
DISPLAY 0.872340 (-6902 4125);
PAINT GREEN (-6902 4125);
DISPLAY INVISIBLE (-6902 4125);
FORCEADD TAP..1
(-7100 4575);
FORCEPROP 3 LASTPIN (-7150 4575) SIG_NAME P5E_CPU0_P2_TX_BUF_DP<12>
J 0
(-7140 4585);
DISPLAY 0.659574 (-7140 4585);
PAINT MONO (-7140 4585);
DISPLAY INVISIBLE (-7140 4585);
FORCEPROP 1 LASTPIN (-7150 4575) BN 12
J 0
(-7162 4583);
DISPLAY 0.680851 (-7162 4583);
PAINT GREEN (-7162 4583);
FORCEPROP 2 LAST CDS_LIB standard
J 0
(-7100 4575);
DISPLAY INVISIBLE (-7100 4575);
FORCEPROP 1 LAST BODY_TYPE PLUMBING
J 0
(-7100 4625);
DISPLAY 0.872340 (-7100 4625);
PAINT GREEN (-7100 4625);
DISPLAY INVISIBLE (-7100 4625);
FORCEPROP 1 LAST HDL_TAP TRUE
J 0
(-6775 4450);
DISPLAY 0.872340 (-6775 4450);
DISPLAY INVISIBLE (-6775 4450);
FORCEPROP 1 LAST PATH I64
J 0
(-7102 4575);
DISPLAY 0.872340 (-7102 4575);
PAINT GREEN (-7102 4575);
DISPLAY INVISIBLE (-7102 4575);
FORCEADD TAP..1
(-6900 4475);
FORCEPROP 3 LASTPIN (-6950 4475) SIG_NAME P5E_CPU0_P2_TX_BUF_DN<12>
J 0
(-6940 4485);
DISPLAY 0.659574 (-6940 4485);
PAINT MONO (-6940 4485);
DISPLAY INVISIBLE (-6940 4485);
FORCEPROP 1 LASTPIN (-6950 4475) BN 12
J 0
(-6962 4483);
DISPLAY 0.680851 (-6962 4483);
PAINT GREEN (-6962 4483);
FORCEPROP 2 LAST CDS_LIB standard
J 0
(-6900 4475);
DISPLAY INVISIBLE (-6900 4475);
FORCEPROP 1 LAST BODY_TYPE PLUMBING
J 0
(-6900 4525);
DISPLAY 0.872340 (-6900 4525);
PAINT GREEN (-6900 4525);
DISPLAY INVISIBLE (-6900 4525);
FORCEPROP 1 LAST HDL_TAP TRUE
J 0
(-6575 4350);
DISPLAY 0.872340 (-6575 4350);
DISPLAY INVISIBLE (-6575 4350);
FORCEPROP 1 LAST PATH I65
J 0
(-6902 4475);
DISPLAY 0.872340 (-6902 4475);
PAINT GREEN (-6902 4475);
DISPLAY INVISIBLE (-6902 4475);
FORCEADD TAP..1
(-6900 4825);
FORCEPROP 3 LASTPIN (-6950 4825) SIG_NAME P5E_CPU0_P2_TX_BUF_DN<13>
J 0
(-6940 4835);
DISPLAY 0.659574 (-6940 4835);
PAINT MONO (-6940 4835);
DISPLAY INVISIBLE (-6940 4835);
FORCEPROP 1 LASTPIN (-6950 4825) BN 13
J 0
(-6962 4833);
DISPLAY 0.680851 (-6962 4833);
PAINT GREEN (-6962 4833);
FORCEPROP 2 LAST CDS_LIB standard
J 0
(-6900 4825);
DISPLAY INVISIBLE (-6900 4825);
FORCEPROP 1 LAST BODY_TYPE PLUMBING
J 0
(-6900 4875);
DISPLAY 0.872340 (-6900 4875);
PAINT GREEN (-6900 4875);
DISPLAY INVISIBLE (-6900 4875);
FORCEPROP 1 LAST HDL_TAP TRUE
J 0
(-6575 4700);
DISPLAY 0.872340 (-6575 4700);
DISPLAY INVISIBLE (-6575 4700);
FORCEPROP 1 LAST PATH I66
J 0
(-6902 4825);
DISPLAY 0.872340 (-6902 4825);
PAINT GREEN (-6902 4825);
DISPLAY INVISIBLE (-6902 4825);
FORCEADD TAP..1
(-7100 4925);
FORCEPROP 3 LASTPIN (-7150 4925) SIG_NAME P5E_CPU0_P2_TX_BUF_DP<13>
J 0
(-7140 4935);
DISPLAY 0.659574 (-7140 4935);
PAINT MONO (-7140 4935);
DISPLAY INVISIBLE (-7140 4935);
FORCEPROP 1 LASTPIN (-7150 4925) BN 13
J 0
(-7162 4933);
DISPLAY 0.680851 (-7162 4933);
PAINT GREEN (-7162 4933);
FORCEPROP 2 LAST CDS_LIB standard
J 0
(-7100 4925);
DISPLAY INVISIBLE (-7100 4925);
FORCEPROP 1 LAST BODY_TYPE PLUMBING
J 0
(-7100 4975);
DISPLAY 0.872340 (-7100 4975);
PAINT GREEN (-7100 4975);
DISPLAY INVISIBLE (-7100 4975);
FORCEPROP 1 LAST HDL_TAP TRUE
J 0
(-6775 4800);
DISPLAY 0.872340 (-6775 4800);
DISPLAY INVISIBLE (-6775 4800);
FORCEPROP 1 LAST PATH I67
J 0
(-7102 4925);
DISPLAY 0.872340 (-7102 4925);
PAINT GREEN (-7102 4925);
DISPLAY INVISIBLE (-7102 4925);
FORCEADD TAP..1
(-7100 5275);
FORCEPROP 3 LASTPIN (-7150 5275) SIG_NAME P5E_CPU0_P2_TX_BUF_DP<14>
J 0
(-7140 5285);
DISPLAY 0.659574 (-7140 5285);
PAINT MONO (-7140 5285);
DISPLAY INVISIBLE (-7140 5285);
FORCEPROP 1 LASTPIN (-7150 5275) BN 14
J 0
(-7162 5283);
DISPLAY 0.680851 (-7162 5283);
PAINT GREEN (-7162 5283);
FORCEPROP 2 LAST CDS_LIB standard
J 0
(-7100 5275);
DISPLAY INVISIBLE (-7100 5275);
FORCEPROP 1 LAST BODY_TYPE PLUMBING
J 0
(-7100 5325);
DISPLAY 0.872340 (-7100 5325);
PAINT GREEN (-7100 5325);
DISPLAY INVISIBLE (-7100 5325);
FORCEPROP 1 LAST HDL_TAP TRUE
J 0
(-6775 5150);
DISPLAY 0.872340 (-6775 5150);
DISPLAY INVISIBLE (-6775 5150);
FORCEPROP 1 LAST PATH I68
J 0
(-7102 5275);
DISPLAY 0.872340 (-7102 5275);
PAINT GREEN (-7102 5275);
DISPLAY INVISIBLE (-7102 5275);
FORCEADD TAP..1
(-6900 5175);
FORCEPROP 3 LASTPIN (-6950 5175) SIG_NAME P5E_CPU0_P2_TX_BUF_DN<14>
J 0
(-6940 5185);
DISPLAY 0.659574 (-6940 5185);
PAINT MONO (-6940 5185);
DISPLAY INVISIBLE (-6940 5185);
FORCEPROP 1 LASTPIN (-6950 5175) BN 14
J 0
(-6962 5183);
DISPLAY 0.680851 (-6962 5183);
PAINT GREEN (-6962 5183);
FORCEPROP 2 LAST CDS_LIB standard
J 0
(-6900 5175);
DISPLAY INVISIBLE (-6900 5175);
FORCEPROP 1 LAST BODY_TYPE PLUMBING
J 0
(-6900 5225);
DISPLAY 0.872340 (-6900 5225);
PAINT GREEN (-6900 5225);
DISPLAY INVISIBLE (-6900 5225);
FORCEPROP 1 LAST HDL_TAP TRUE
J 0
(-6575 5050);
DISPLAY 0.872340 (-6575 5050);
DISPLAY INVISIBLE (-6575 5050);
FORCEPROP 1 LAST PATH I69
J 0
(-6902 5175);
DISPLAY 0.872340 (-6902 5175);
PAINT GREEN (-6902 5175);
DISPLAY INVISIBLE (-6902 5175);
FORCEADD TAP..1
R 2
(-3250 900);
FORCEPROP 3 LASTPIN (-3200 900) SIG_NAME P5E_CPU0_P2_TX_BUF_DN<5>
J 0
(-3190 910);
DISPLAY 0.659574 (-3190 910);
PAINT MONO (-3190 910);
DISPLAY INVISIBLE (-3190 910);
FORCEPROP 1 LASTPIN (-3200 900) BN 5
J 2
(-3188 908);
DISPLAY 0.680851 (-3188 908);
PAINT GREEN (-3188 908);
FORCEPROP 2 LAST CDS_LIB standard
J 0
(-3250 900);
DISPLAY INVISIBLE (-3250 900);
FORCEPROP 1 LAST BODY_TYPE PLUMBING
J 2
(-3250 950);
DISPLAY 0.872340 (-3250 950);
PAINT GREEN (-3250 950);
DISPLAY INVISIBLE (-3250 950);
FORCEPROP 1 LAST HDL_TAP TRUE
J 2
(-3575 775);
DISPLAY 0.872340 (-3575 775);
DISPLAY INVISIBLE (-3575 775);
FORCEPROP 1 LAST PATH I7
J 2
(-3248 900);
DISPLAY 0.872340 (-3248 900);
PAINT GREEN (-3248 900);
DISPLAY INVISIBLE (-3248 900);
FORCEADD TAP..1
(-7100 5625);
FORCEPROP 3 LASTPIN (-7150 5625) SIG_NAME P5E_CPU0_P2_TX_BUF_DP<15>
J 0
(-7140 5635);
DISPLAY 0.659574 (-7140 5635);
PAINT MONO (-7140 5635);
DISPLAY INVISIBLE (-7140 5635);
FORCEPROP 1 LASTPIN (-7150 5625) BN 15
J 0
(-7162 5633);
DISPLAY 0.680851 (-7162 5633);
PAINT GREEN (-7162 5633);
FORCEPROP 2 LAST CDS_LIB standard
J 0
(-7100 5625);
DISPLAY INVISIBLE (-7100 5625);
FORCEPROP 1 LAST BODY_TYPE PLUMBING
J 0
(-7100 5675);
DISPLAY 0.872340 (-7100 5675);
PAINT GREEN (-7100 5675);
DISPLAY INVISIBLE (-7100 5675);
FORCEPROP 1 LAST HDL_TAP TRUE
J 0
(-6775 5500);
DISPLAY 0.872340 (-6775 5500);
DISPLAY INVISIBLE (-6775 5500);
FORCEPROP 1 LAST PATH I70
J 0
(-7102 5625);
DISPLAY 0.872340 (-7102 5625);
PAINT GREEN (-7102 5625);
DISPLAY INVISIBLE (-7102 5625);
FORCEADD TAP..1
(-6900 5525);
FORCEPROP 3 LASTPIN (-6950 5525) SIG_NAME P5E_CPU0_P2_TX_BUF_DN<15>
J 0
(-6940 5535);
DISPLAY 0.659574 (-6940 5535);
PAINT MONO (-6940 5535);
DISPLAY INVISIBLE (-6940 5535);
FORCEPROP 1 LASTPIN (-6950 5525) BN 15
J 0
(-6962 5533);
DISPLAY 0.680851 (-6962 5533);
PAINT GREEN (-6962 5533);
FORCEPROP 2 LAST CDS_LIB standard
J 0
(-6900 5525);
DISPLAY INVISIBLE (-6900 5525);
FORCEPROP 1 LAST BODY_TYPE PLUMBING
J 0
(-6900 5575);
DISPLAY 0.872340 (-6900 5575);
PAINT GREEN (-6900 5575);
DISPLAY INVISIBLE (-6900 5575);
FORCEPROP 1 LAST HDL_TAP TRUE
J 0
(-6575 5400);
DISPLAY 0.872340 (-6575 5400);
DISPLAY INVISIBLE (-6575 5400);
FORCEPROP 1 LAST PATH I71
J 0
(-6902 5525);
DISPLAY 0.872340 (-6902 5525);
PAINT GREEN (-6902 5525);
DISPLAY INVISIBLE (-6902 5525);
FORCEADD OFFPAGE..5
R 2
(-5900 5650);
FORCEPROP 2 LAST $XR0 298 
J 0
(-5711 5650);
DISPLAY 0.638298 (-5711 5650);
PAINT MONO (-5711 5650);
FORCEPROP 2 LAST CDS_LIB standard
J 0
(-5900 5650);
DISPLAY INVISIBLE (-5900 5650);
FORCEPROP 1 LAST OFFPAGE TRUE
J 2
(-6225 5525);
DISPLAY 0.872340 (-6225 5525);
PAINT GREEN (-6225 5525);
DISPLAY INVISIBLE (-6225 5525);
FORCEPROP 1 LAST COMMENT_BODY TRUE
J 2
(-6000 5575);
DISPLAY 0.872340 (-6000 5575);
PAINT GREEN (-6000 5575);
DISPLAY INVISIBLE (-6000 5575);
FORCEPROP 2 LAST PATH I72
J 0
(-5725 5725);
DISPLAY 0.680851 (-5725 5725);
DISPLAY INVISIBLE (-5725 5725);
FORCEADD OFFPAGE..5
R 2
(-5925 5550);
FORCEPROP 2 LAST $XR0 298 
J 0
(-5736 5550);
DISPLAY 0.638298 (-5736 5550);
PAINT MONO (-5736 5550);
FORCEPROP 2 LAST CDS_LIB standard
J 0
(-5925 5550);
DISPLAY INVISIBLE (-5925 5550);
FORCEPROP 1 LAST OFFPAGE TRUE
J 2
(-6250 5425);
DISPLAY 0.872340 (-6250 5425);
PAINT GREEN (-6250 5425);
DISPLAY INVISIBLE (-6250 5425);
FORCEPROP 1 LAST COMMENT_BODY TRUE
J 2
(-6025 5475);
DISPLAY 0.872340 (-6025 5475);
PAINT GREEN (-6025 5475);
DISPLAY INVISIBLE (-6025 5475);
FORCEPROP 2 LAST PATH I73
J 0
(-5750 5625);
DISPLAY 0.680851 (-5750 5625);
DISPLAY INVISIBLE (-5750 5625);
FORCEADD TAP..1
R 2
(-8100 575);
FORCEPROP 3 LASTPIN (-8050 575) SIG_NAME P5E_CPU0_P2_TX_BUF_DN<15>
J 0
(-8040 585);
DISPLAY 0.659574 (-8040 585);
PAINT MONO (-8040 585);
DISPLAY INVISIBLE (-8040 585);
FORCEPROP 1 LASTPIN (-8050 575) BN 15
J 2
(-8038 583);
DISPLAY 0.680851 (-8038 583);
PAINT GREEN (-8038 583);
FORCEPROP 2 LAST CDS_LIB standard
J 0
(-8100 575);
DISPLAY INVISIBLE (-8100 575);
FORCEPROP 1 LAST BODY_TYPE PLUMBING
J 2
(-8100 625);
DISPLAY 0.872340 (-8100 625);
PAINT GREEN (-8100 625);
DISPLAY INVISIBLE (-8100 625);
FORCEPROP 1 LAST HDL_TAP TRUE
J 2
(-8425 450);
DISPLAY 0.872340 (-8425 450);
DISPLAY INVISIBLE (-8425 450);
FORCEPROP 1 LAST PATH I74
J 2
(-8098 575);
DISPLAY 0.872340 (-8098 575);
PAINT GREEN (-8098 575);
DISPLAY INVISIBLE (-8098 575);
FORCEADD TAP..1
R 2
(-8100 775);
FORCEPROP 3 LASTPIN (-8050 775) SIG_NAME P5E_CPU0_P2_TX_BUF_DN<14>
J 0
(-8040 785);
DISPLAY 0.659574 (-8040 785);
PAINT MONO (-8040 785);
DISPLAY INVISIBLE (-8040 785);
FORCEPROP 1 LASTPIN (-8050 775) BN 14
J 2
(-8038 783);
DISPLAY 0.680851 (-8038 783);
PAINT GREEN (-8038 783);
FORCEPROP 2 LAST CDS_LIB standard
J 0
(-8100 775);
DISPLAY INVISIBLE (-8100 775);
FORCEPROP 1 LAST BODY_TYPE PLUMBING
J 2
(-8100 825);
DISPLAY 0.872340 (-8100 825);
PAINT GREEN (-8100 825);
DISPLAY INVISIBLE (-8100 825);
FORCEPROP 1 LAST HDL_TAP TRUE
J 2
(-8425 650);
DISPLAY 0.872340 (-8425 650);
DISPLAY INVISIBLE (-8425 650);
FORCEPROP 1 LAST PATH I75
J 2
(-8098 775);
DISPLAY 0.872340 (-8098 775);
PAINT GREEN (-8098 775);
DISPLAY INVISIBLE (-8098 775);
FORCEADD TAP..1
R 2
(-7850 625);
FORCEPROP 3 LASTPIN (-7800 625) SIG_NAME P5E_CPU0_P2_TX_BUF_DP<15>
J 0
(-7790 635);
DISPLAY 0.659574 (-7790 635);
PAINT MONO (-7790 635);
DISPLAY INVISIBLE (-7790 635);
FORCEPROP 1 LASTPIN (-7800 625) BN 15
J 2
(-7788 633);
DISPLAY 0.680851 (-7788 633);
PAINT GREEN (-7788 633);
FORCEPROP 2 LAST CDS_LIB standard
J 0
(-7850 625);
DISPLAY INVISIBLE (-7850 625);
FORCEPROP 1 LAST BODY_TYPE PLUMBING
J 2
(-7850 675);
DISPLAY 0.872340 (-7850 675);
PAINT GREEN (-7850 675);
DISPLAY INVISIBLE (-7850 675);
FORCEPROP 1 LAST HDL_TAP TRUE
J 2
(-8175 500);
DISPLAY 0.872340 (-8175 500);
DISPLAY INVISIBLE (-8175 500);
FORCEPROP 1 LAST PATH I76
J 2
(-7848 625);
DISPLAY 0.872340 (-7848 625);
PAINT GREEN (-7848 625);
DISPLAY INVISIBLE (-7848 625);
FORCEADD TAP..1
R 2
(-7850 825);
FORCEPROP 3 LASTPIN (-7800 825) SIG_NAME P5E_CPU0_P2_TX_BUF_DP<14>
J 0
(-7790 835);
DISPLAY 0.659574 (-7790 835);
PAINT MONO (-7790 835);
DISPLAY INVISIBLE (-7790 835);
FORCEPROP 1 LASTPIN (-7800 825) BN 14
J 2
(-7788 833);
DISPLAY 0.680851 (-7788 833);
PAINT GREEN (-7788 833);
FORCEPROP 2 LAST CDS_LIB standard
J 0
(-7850 825);
DISPLAY INVISIBLE (-7850 825);
FORCEPROP 1 LAST BODY_TYPE PLUMBING
J 2
(-7850 875);
DISPLAY 0.872340 (-7850 875);
PAINT GREEN (-7850 875);
DISPLAY INVISIBLE (-7850 875);
FORCEPROP 1 LAST HDL_TAP TRUE
J 2
(-8175 700);
DISPLAY 0.872340 (-8175 700);
DISPLAY INVISIBLE (-8175 700);
FORCEPROP 1 LAST PATH I77
J 2
(-7848 825);
DISPLAY 0.872340 (-7848 825);
PAINT GREEN (-7848 825);
DISPLAY INVISIBLE (-7848 825);
FORCEADD TAP..1
R 2
(-8100 1375);
FORCEPROP 3 LASTPIN (-8050 1375) SIG_NAME P5E_CPU0_P2_TX_BUF_DN<11>
J 0
(-8040 1385);
DISPLAY 0.659574 (-8040 1385);
PAINT MONO (-8040 1385);
DISPLAY INVISIBLE (-8040 1385);
FORCEPROP 1 LASTPIN (-8050 1375) BN 11
J 2
(-8038 1383);
DISPLAY 0.680851 (-8038 1383);
PAINT GREEN (-8038 1383);
FORCEPROP 2 LAST CDS_LIB standard
J 0
(-8100 1375);
DISPLAY INVISIBLE (-8100 1375);
FORCEPROP 1 LAST BODY_TYPE PLUMBING
J 2
(-8100 1425);
DISPLAY 0.872340 (-8100 1425);
PAINT GREEN (-8100 1425);
DISPLAY INVISIBLE (-8100 1425);
FORCEPROP 1 LAST HDL_TAP TRUE
J 2
(-8425 1250);
DISPLAY 0.872340 (-8425 1250);
DISPLAY INVISIBLE (-8425 1250);
FORCEPROP 1 LAST PATH I78
J 2
(-8098 1375);
DISPLAY 0.872340 (-8098 1375);
PAINT GREEN (-8098 1375);
DISPLAY INVISIBLE (-8098 1375);
FORCEADD TAP..1
R 2
(-8100 1175);
FORCEPROP 3 LASTPIN (-8050 1175) SIG_NAME P5E_CPU0_P2_TX_BUF_DN<12>
J 0
(-8040 1185);
DISPLAY 0.659574 (-8040 1185);
PAINT MONO (-8040 1185);
DISPLAY INVISIBLE (-8040 1185);
FORCEPROP 1 LASTPIN (-8050 1175) BN 12
J 2
(-8038 1183);
DISPLAY 0.680851 (-8038 1183);
PAINT GREEN (-8038 1183);
FORCEPROP 2 LAST CDS_LIB standard
J 0
(-8100 1175);
DISPLAY INVISIBLE (-8100 1175);
FORCEPROP 1 LAST BODY_TYPE PLUMBING
J 2
(-8100 1225);
DISPLAY 0.872340 (-8100 1225);
PAINT GREEN (-8100 1225);
DISPLAY INVISIBLE (-8100 1225);
FORCEPROP 1 LAST HDL_TAP TRUE
J 2
(-8425 1050);
DISPLAY 0.872340 (-8425 1050);
DISPLAY INVISIBLE (-8425 1050);
FORCEPROP 1 LAST PATH I79
J 2
(-8098 1175);
DISPLAY 0.872340 (-8098 1175);
PAINT GREEN (-8098 1175);
DISPLAY INVISIBLE (-8098 1175);
FORCEADD TAP..1
R 2
(-3250 1100);
FORCEPROP 3 LASTPIN (-3200 1100) SIG_NAME P5E_CPU0_P2_TX_BUF_DN<4>
J 0
(-3190 1110);
DISPLAY 0.659574 (-3190 1110);
PAINT MONO (-3190 1110);
DISPLAY INVISIBLE (-3190 1110);
FORCEPROP 1 LASTPIN (-3200 1100) BN 4
J 2
(-3188 1108);
DISPLAY 0.680851 (-3188 1108);
PAINT GREEN (-3188 1108);
FORCEPROP 2 LAST CDS_LIB standard
J 0
(-3250 1100);
DISPLAY INVISIBLE (-3250 1100);
FORCEPROP 1 LAST BODY_TYPE PLUMBING
J 2
(-3250 1150);
DISPLAY 0.872340 (-3250 1150);
PAINT GREEN (-3250 1150);
DISPLAY INVISIBLE (-3250 1150);
FORCEPROP 1 LAST HDL_TAP TRUE
J 2
(-3575 975);
DISPLAY 0.872340 (-3575 975);
DISPLAY INVISIBLE (-3575 975);
FORCEPROP 1 LAST PATH I8
J 2
(-3248 1100);
DISPLAY 0.872340 (-3248 1100);
PAINT GREEN (-3248 1100);
DISPLAY INVISIBLE (-3248 1100);
FORCEADD TAP..1
R 2
(-8100 975);
FORCEPROP 3 LASTPIN (-8050 975) SIG_NAME P5E_CPU0_P2_TX_BUF_DN<13>
J 0
(-8040 985);
DISPLAY 0.659574 (-8040 985);
PAINT MONO (-8040 985);
DISPLAY INVISIBLE (-8040 985);
FORCEPROP 1 LASTPIN (-8050 975) BN 13
J 2
(-8038 983);
DISPLAY 0.680851 (-8038 983);
PAINT GREEN (-8038 983);
FORCEPROP 2 LAST CDS_LIB standard
J 0
(-8100 975);
DISPLAY INVISIBLE (-8100 975);
FORCEPROP 1 LAST BODY_TYPE PLUMBING
J 2
(-8100 1025);
DISPLAY 0.872340 (-8100 1025);
PAINT GREEN (-8100 1025);
DISPLAY INVISIBLE (-8100 1025);
FORCEPROP 1 LAST HDL_TAP TRUE
J 2
(-8425 850);
DISPLAY 0.872340 (-8425 850);
DISPLAY INVISIBLE (-8425 850);
FORCEPROP 1 LAST PATH I80
J 2
(-8098 975);
DISPLAY 0.872340 (-8098 975);
PAINT GREEN (-8098 975);
DISPLAY INVISIBLE (-8098 975);
FORCEADD TAP..1
R 2
(-7850 1025);
FORCEPROP 3 LASTPIN (-7800 1025) SIG_NAME P5E_CPU0_P2_TX_BUF_DP<13>
J 0
(-7790 1035);
DISPLAY 0.659574 (-7790 1035);
PAINT MONO (-7790 1035);
DISPLAY INVISIBLE (-7790 1035);
FORCEPROP 1 LASTPIN (-7800 1025) BN 13
J 2
(-7788 1033);
DISPLAY 0.680851 (-7788 1033);
PAINT GREEN (-7788 1033);
FORCEPROP 2 LAST CDS_LIB standard
J 0
(-7850 1025);
DISPLAY INVISIBLE (-7850 1025);
FORCEPROP 1 LAST BODY_TYPE PLUMBING
J 2
(-7850 1075);
DISPLAY 0.872340 (-7850 1075);
PAINT GREEN (-7850 1075);
DISPLAY INVISIBLE (-7850 1075);
FORCEPROP 1 LAST HDL_TAP TRUE
J 2
(-8175 900);
DISPLAY 0.872340 (-8175 900);
DISPLAY INVISIBLE (-8175 900);
FORCEPROP 1 LAST PATH I81
J 2
(-7848 1025);
DISPLAY 0.872340 (-7848 1025);
PAINT GREEN (-7848 1025);
DISPLAY INVISIBLE (-7848 1025);
FORCEADD TAP..1
R 2
(-7850 1225);
FORCEPROP 3 LASTPIN (-7800 1225) SIG_NAME P5E_CPU0_P2_TX_BUF_DP<12>
J 0
(-7790 1235);
DISPLAY 0.659574 (-7790 1235);
PAINT MONO (-7790 1235);
DISPLAY INVISIBLE (-7790 1235);
FORCEPROP 1 LASTPIN (-7800 1225) BN 12
J 2
(-7788 1233);
DISPLAY 0.680851 (-7788 1233);
PAINT GREEN (-7788 1233);
FORCEPROP 2 LAST CDS_LIB standard
J 0
(-7850 1225);
DISPLAY INVISIBLE (-7850 1225);
FORCEPROP 1 LAST BODY_TYPE PLUMBING
J 2
(-7850 1275);
DISPLAY 0.872340 (-7850 1275);
PAINT GREEN (-7850 1275);
DISPLAY INVISIBLE (-7850 1275);
FORCEPROP 1 LAST HDL_TAP TRUE
J 2
(-8175 1100);
DISPLAY 0.872340 (-8175 1100);
DISPLAY INVISIBLE (-8175 1100);
FORCEPROP 1 LAST PATH I82
J 2
(-7848 1225);
DISPLAY 0.872340 (-7848 1225);
PAINT GREEN (-7848 1225);
DISPLAY INVISIBLE (-7848 1225);
FORCEADD TAP..1
R 2
(-8100 1775);
FORCEPROP 3 LASTPIN (-8050 1775) SIG_NAME P5E_CPU0_P2_TX_BUF_DN<9>
J 0
(-8040 1785);
DISPLAY 0.659574 (-8040 1785);
PAINT MONO (-8040 1785);
DISPLAY INVISIBLE (-8040 1785);
FORCEPROP 1 LASTPIN (-8050 1775) BN 9
J 2
(-8038 1783);
DISPLAY 0.680851 (-8038 1783);
PAINT GREEN (-8038 1783);
FORCEPROP 2 LAST CDS_LIB standard
J 0
(-8100 1775);
DISPLAY INVISIBLE (-8100 1775);
FORCEPROP 1 LAST BODY_TYPE PLUMBING
J 2
(-8100 1825);
DISPLAY 0.872340 (-8100 1825);
PAINT GREEN (-8100 1825);
DISPLAY INVISIBLE (-8100 1825);
FORCEPROP 1 LAST HDL_TAP TRUE
J 2
(-8425 1650);
DISPLAY 0.872340 (-8425 1650);
DISPLAY INVISIBLE (-8425 1650);
FORCEPROP 1 LAST PATH I83
J 2
(-8098 1775);
DISPLAY 0.872340 (-8098 1775);
PAINT GREEN (-8098 1775);
DISPLAY INVISIBLE (-8098 1775);
FORCEADD TAP..1
R 2
(-8100 1575);
FORCEPROP 3 LASTPIN (-8050 1575) SIG_NAME P5E_CPU0_P2_TX_BUF_DN<10>
J 0
(-8040 1585);
DISPLAY 0.659574 (-8040 1585);
PAINT MONO (-8040 1585);
DISPLAY INVISIBLE (-8040 1585);
FORCEPROP 1 LASTPIN (-8050 1575) BN 10
J 2
(-8038 1583);
DISPLAY 0.680851 (-8038 1583);
PAINT GREEN (-8038 1583);
FORCEPROP 2 LAST CDS_LIB standard
J 0
(-8100 1575);
DISPLAY INVISIBLE (-8100 1575);
FORCEPROP 1 LAST BODY_TYPE PLUMBING
J 2
(-8100 1625);
DISPLAY 0.872340 (-8100 1625);
PAINT GREEN (-8100 1625);
DISPLAY INVISIBLE (-8100 1625);
FORCEPROP 1 LAST HDL_TAP TRUE
J 2
(-8425 1450);
DISPLAY 0.872340 (-8425 1450);
DISPLAY INVISIBLE (-8425 1450);
FORCEPROP 1 LAST PATH I84
J 2
(-8098 1575);
DISPLAY 0.872340 (-8098 1575);
PAINT GREEN (-8098 1575);
DISPLAY INVISIBLE (-8098 1575);
FORCEADD TAP..1
R 2
(-7850 1425);
FORCEPROP 3 LASTPIN (-7800 1425) SIG_NAME P5E_CPU0_P2_TX_BUF_DP<11>
J 0
(-7790 1435);
DISPLAY 0.659574 (-7790 1435);
PAINT MONO (-7790 1435);
DISPLAY INVISIBLE (-7790 1435);
FORCEPROP 1 LASTPIN (-7800 1425) BN 11
J 2
(-7788 1433);
DISPLAY 0.680851 (-7788 1433);
PAINT GREEN (-7788 1433);
FORCEPROP 2 LAST CDS_LIB standard
J 0
(-7850 1425);
DISPLAY INVISIBLE (-7850 1425);
FORCEPROP 1 LAST BODY_TYPE PLUMBING
J 2
(-7850 1475);
DISPLAY 0.872340 (-7850 1475);
PAINT GREEN (-7850 1475);
DISPLAY INVISIBLE (-7850 1475);
FORCEPROP 1 LAST HDL_TAP TRUE
J 2
(-8175 1300);
DISPLAY 0.872340 (-8175 1300);
DISPLAY INVISIBLE (-8175 1300);
FORCEPROP 1 LAST PATH I85
J 2
(-7848 1425);
DISPLAY 0.872340 (-7848 1425);
PAINT GREEN (-7848 1425);
DISPLAY INVISIBLE (-7848 1425);
FORCEADD TAP..1
R 2
(-7850 1625);
FORCEPROP 3 LASTPIN (-7800 1625) SIG_NAME P5E_CPU0_P2_TX_BUF_DP<10>
J 0
(-7790 1635);
DISPLAY 0.659574 (-7790 1635);
PAINT MONO (-7790 1635);
DISPLAY INVISIBLE (-7790 1635);
FORCEPROP 1 LASTPIN (-7800 1625) BN 10
J 2
(-7788 1633);
DISPLAY 0.680851 (-7788 1633);
PAINT GREEN (-7788 1633);
FORCEPROP 2 LAST CDS_LIB standard
J 0
(-7850 1625);
DISPLAY INVISIBLE (-7850 1625);
FORCEPROP 1 LAST BODY_TYPE PLUMBING
J 2
(-7850 1675);
DISPLAY 0.872340 (-7850 1675);
PAINT GREEN (-7850 1675);
DISPLAY INVISIBLE (-7850 1675);
FORCEPROP 1 LAST HDL_TAP TRUE
J 2
(-8175 1500);
DISPLAY 0.872340 (-8175 1500);
DISPLAY INVISIBLE (-8175 1500);
FORCEPROP 1 LAST PATH I86
J 2
(-7848 1625);
DISPLAY 0.872340 (-7848 1625);
PAINT GREEN (-7848 1625);
DISPLAY INVISIBLE (-7848 1625);
FORCEADD TAP..1
R 2
(-7850 1825);
FORCEPROP 3 LASTPIN (-7800 1825) SIG_NAME P5E_CPU0_P2_TX_BUF_DP<9>
J 0
(-7790 1835);
DISPLAY 0.659574 (-7790 1835);
PAINT MONO (-7790 1835);
DISPLAY INVISIBLE (-7790 1835);
FORCEPROP 1 LASTPIN (-7800 1825) BN 9
J 2
(-7788 1833);
DISPLAY 0.680851 (-7788 1833);
PAINT GREEN (-7788 1833);
FORCEPROP 2 LAST CDS_LIB standard
J 0
(-7850 1825);
DISPLAY INVISIBLE (-7850 1825);
FORCEPROP 1 LAST BODY_TYPE PLUMBING
J 2
(-7850 1875);
DISPLAY 0.872340 (-7850 1875);
PAINT GREEN (-7850 1875);
DISPLAY INVISIBLE (-7850 1875);
FORCEPROP 1 LAST HDL_TAP TRUE
J 2
(-8175 1700);
DISPLAY 0.872340 (-8175 1700);
DISPLAY INVISIBLE (-8175 1700);
FORCEPROP 1 LAST PATH I87
J 2
(-7848 1825);
DISPLAY 0.872340 (-7848 1825);
PAINT GREEN (-7848 1825);
DISPLAY INVISIBLE (-7848 1825);
FORCEADD Q_CAP_DIFFBUS..2
R 2
(-7125 575);
FORCEPROP 1 LAST LOCATION C6596
J 2
(-6850 575);
DISPLAY 0.723404 (-6850 575);
PAINT GREEN (-6850 575);
FORCEPROP 2 LAST $SEC 1
J 2
(-6950 650);
DISPLAY 0.680851 (-6950 650);
PAINT MONO (-6950 650);
DISPLAY INVISIBLE (-6950 650);
FORCEPROP 2 LAST CDS_SEC 1
J 2
(-6950 650);
DISPLAY 0.680851 (-6950 650);
DISPLAY INVISIBLE (-6950 650);
FORCEPROP 2 LASTPIN (-7050 575) $PN 1
J 0
(-7040 585);
DISPLAY 0.808511 (-7040 585);
FORCEPROP 2 LASTPIN (-7200 575) $PN 2
J 2
(-7210 585);
DISPLAY 0.808511 (-7210 585);
FORCEPROP 2 LAST VALUE DIFF BUS_0.22UF
J 2
(-7275 575);
DISPLAY 0.553191 (-7275 575);
FORCEPROP 2 LAST TOLERANCE 20%
J 2
(-7200 625);
DISPLAY 0.553191 (-7200 625);
DISPLAY INVISIBLE (-7200 625);
FORCEPROP 2 LAST PACK_TYPE C0201
J 2
(-7300 625);
DISPLAY 0.553191 (-7300 625);
DISPLAY INVISIBLE (-7300 625);
FORCEPROP 1 LAST MATERIAL X6S
J 2
(-7116 654);
DISPLAY 0.574468 (-7116 654);
PAINT GREEN (-7116 654);
DISPLAY INVISIBLE (-7116 654);
FORCEPROP 2 LAST VOLTAGE 6.3V
J 2
(-7475 625);
DISPLAY 0.553191 (-7475 625);
DISPLAY INVISIBLE (-7475 625);
FORCEPROP 1 LAST PIN_NAMES_ROTATE TRUE
J 2
(-7125 575);
DISPLAY 0.489362 (-7125 575);
PAINT GREEN (-7125 575);
DISPLAY INVISIBLE (-7125 575);
FORCEPROP 2 LAST CDS_LIB pure_quanta
J 2
(-7125 575);
DISPLAY INVISIBLE (-7125 575);
FORCEPROP 1 LAST CDS_LMAN_SYM_OUTLINE -25,50,25,-50
J 2
(-7125 575);
DISPLAY 0.468085 (-7125 575);
PAINT GREEN (-7125 575);
DISPLAY INVISIBLE (-7125 575);
FORCEPROP 1 LAST PATH I88
J 2
(-7125 575);
DISPLAY 0.723404 (-7125 575);
DISPLAY INVISIBLE (-7125 575);
FORCEPROP 1 LAST PART_NUMBER SP_CH4221MEE01
J 2
(-7241 663);
DISPLAY 0.574468 (-7241 663);
PAINT GREEN (-7241 663);
DISPLAY INVISIBLE (-7241 663);
FORCEPROP 1 LAST LOCATION C6596
J 0
(-6875 650);
DISPLAY 1.021277 (-6875 650);
DISPLAY INVISIBLE (-6875 650);
FORCEADD Q_CAP_DIFFBUS..2
R 2
(-7125 625);
FORCEPROP 1 LAST LOCATION C6595
J 2
(-6850 625);
DISPLAY 0.723404 (-6850 625);
PAINT GREEN (-6850 625);
FORCEPROP 2 LAST $SEC 1
J 2
(-6950 700);
DISPLAY 0.680851 (-6950 700);
PAINT MONO (-6950 700);
DISPLAY INVISIBLE (-6950 700);
FORCEPROP 2 LAST CDS_SEC 1
J 2
(-6950 700);
DISPLAY 0.680851 (-6950 700);
DISPLAY INVISIBLE (-6950 700);
FORCEPROP 2 LASTPIN (-7050 625) $PN 1
J 0
(-7040 635);
DISPLAY 0.808511 (-7040 635);
FORCEPROP 2 LASTPIN (-7200 625) $PN 2
J 2
(-7210 635);
DISPLAY 0.808511 (-7210 635);
FORCEPROP 2 LAST VALUE DIFF BUS_0.22UF
J 2
(-7275 625);
DISPLAY 0.553191 (-7275 625);
FORCEPROP 2 LAST TOLERANCE 20%
J 2
(-7200 675);
DISPLAY 0.553191 (-7200 675);
DISPLAY INVISIBLE (-7200 675);
FORCEPROP 2 LAST PACK_TYPE C0201
J 2
(-7300 675);
DISPLAY 0.553191 (-7300 675);
DISPLAY INVISIBLE (-7300 675);
FORCEPROP 1 LAST MATERIAL X6S
J 2
(-7116 704);
DISPLAY 0.574468 (-7116 704);
PAINT GREEN (-7116 704);
DISPLAY INVISIBLE (-7116 704);
FORCEPROP 2 LAST VOLTAGE 6.3V
J 2
(-7475 675);
DISPLAY 0.553191 (-7475 675);
DISPLAY INVISIBLE (-7475 675);
FORCEPROP 1 LAST PIN_NAMES_ROTATE TRUE
J 2
(-7125 625);
DISPLAY 0.489362 (-7125 625);
PAINT GREEN (-7125 625);
DISPLAY INVISIBLE (-7125 625);
FORCEPROP 2 LAST CDS_LIB pure_quanta
J 2
(-7125 625);
DISPLAY INVISIBLE (-7125 625);
FORCEPROP 1 LAST CDS_LMAN_SYM_OUTLINE -25,50,25,-50
J 2
(-7125 625);
DISPLAY 0.468085 (-7125 625);
PAINT GREEN (-7125 625);
DISPLAY INVISIBLE (-7125 625);
FORCEPROP 1 LAST PATH I89
J 2
(-7125 625);
DISPLAY 0.723404 (-7125 625);
DISPLAY INVISIBLE (-7125 625);
FORCEPROP 1 LAST PART_NUMBER SP_CH4221MEE01
J 2
(-7241 713);
DISPLAY 0.574468 (-7241 713);
PAINT GREEN (-7241 713);
DISPLAY INVISIBLE (-7241 713);
FORCEPROP 1 LAST LOCATION C6595
J 0
(-6875 700);
DISPLAY 1.021277 (-6875 700);
DISPLAY INVISIBLE (-6875 700);
FORCEADD TAP..1
R 2
(-3250 1300);
FORCEPROP 3 LASTPIN (-3200 1300) SIG_NAME P5E_CPU0_P2_TX_BUF_DN<3>
J 0
(-3190 1310);
DISPLAY 0.659574 (-3190 1310);
PAINT MONO (-3190 1310);
DISPLAY INVISIBLE (-3190 1310);
FORCEPROP 1 LASTPIN (-3200 1300) BN 3
J 2
(-3188 1308);
DISPLAY 0.680851 (-3188 1308);
PAINT GREEN (-3188 1308);
FORCEPROP 2 LAST CDS_LIB standard
J 0
(-3250 1300);
DISPLAY INVISIBLE (-3250 1300);
FORCEPROP 1 LAST BODY_TYPE PLUMBING
J 2
(-3250 1350);
DISPLAY 0.872340 (-3250 1350);
PAINT GREEN (-3250 1350);
DISPLAY INVISIBLE (-3250 1350);
FORCEPROP 1 LAST HDL_TAP TRUE
J 2
(-3575 1175);
DISPLAY 0.872340 (-3575 1175);
DISPLAY INVISIBLE (-3575 1175);
FORCEPROP 1 LAST PATH I9
J 2
(-3248 1300);
DISPLAY 0.872340 (-3248 1300);
PAINT GREEN (-3248 1300);
DISPLAY INVISIBLE (-3248 1300);
FORCEADD Q_CAP_DIFFBUS..2
R 2
(-7125 775);
FORCEPROP 1 LAST LOCATION C6594
J 2
(-6850 775);
DISPLAY 0.723404 (-6850 775);
PAINT GREEN (-6850 775);
FORCEPROP 2 LAST $SEC 1
J 2
(-6950 850);
DISPLAY 0.680851 (-6950 850);
PAINT MONO (-6950 850);
DISPLAY INVISIBLE (-6950 850);
FORCEPROP 2 LAST CDS_SEC 1
J 2
(-6950 850);
DISPLAY 0.680851 (-6950 850);
DISPLAY INVISIBLE (-6950 850);
FORCEPROP 2 LASTPIN (-7050 775) $PN 1
J 0
(-7040 785);
DISPLAY 0.808511 (-7040 785);
FORCEPROP 2 LASTPIN (-7200 775) $PN 2
J 2
(-7210 785);
DISPLAY 0.808511 (-7210 785);
FORCEPROP 2 LAST VALUE DIFF BUS_0.22UF
J 2
(-7275 775);
DISPLAY 0.553191 (-7275 775);
FORCEPROP 2 LAST TOLERANCE 20%
J 2
(-7200 825);
DISPLAY 0.553191 (-7200 825);
DISPLAY INVISIBLE (-7200 825);
FORCEPROP 2 LAST PACK_TYPE C0201
J 2
(-7300 825);
DISPLAY 0.553191 (-7300 825);
DISPLAY INVISIBLE (-7300 825);
FORCEPROP 1 LAST MATERIAL X6S
J 2
(-7116 854);
DISPLAY 0.574468 (-7116 854);
PAINT GREEN (-7116 854);
DISPLAY INVISIBLE (-7116 854);
FORCEPROP 2 LAST VOLTAGE 6.3V
J 2
(-7475 825);
DISPLAY 0.553191 (-7475 825);
DISPLAY INVISIBLE (-7475 825);
FORCEPROP 1 LAST PIN_NAMES_ROTATE TRUE
J 2
(-7125 775);
DISPLAY 0.489362 (-7125 775);
PAINT GREEN (-7125 775);
DISPLAY INVISIBLE (-7125 775);
FORCEPROP 2 LAST CDS_LIB pure_quanta
J 2
(-7125 775);
DISPLAY INVISIBLE (-7125 775);
FORCEPROP 1 LAST CDS_LMAN_SYM_OUTLINE -25,50,25,-50
J 2
(-7125 775);
DISPLAY 0.468085 (-7125 775);
PAINT GREEN (-7125 775);
DISPLAY INVISIBLE (-7125 775);
FORCEPROP 1 LAST PATH I90
J 2
(-7125 775);
DISPLAY 0.723404 (-7125 775);
DISPLAY INVISIBLE (-7125 775);
FORCEPROP 1 LAST PART_NUMBER SP_CH4221MEE01
J 2
(-7241 863);
DISPLAY 0.574468 (-7241 863);
PAINT GREEN (-7241 863);
DISPLAY INVISIBLE (-7241 863);
FORCEPROP 1 LAST LOCATION C6594
J 0
(-6875 850);
DISPLAY 1.021277 (-6875 850);
DISPLAY INVISIBLE (-6875 850);
FORCEADD Q_CAP_DIFFBUS..2
R 2
(-7125 825);
FORCEPROP 1 LAST LOCATION C6593
J 2
(-6850 825);
DISPLAY 0.723404 (-6850 825);
PAINT GREEN (-6850 825);
FORCEPROP 2 LAST $SEC 1
J 2
(-6950 900);
DISPLAY 0.680851 (-6950 900);
PAINT MONO (-6950 900);
DISPLAY INVISIBLE (-6950 900);
FORCEPROP 2 LAST CDS_SEC 1
J 2
(-6950 900);
DISPLAY 0.680851 (-6950 900);
DISPLAY INVISIBLE (-6950 900);
FORCEPROP 2 LASTPIN (-7050 825) $PN 1
J 0
(-7040 835);
DISPLAY 0.808511 (-7040 835);
FORCEPROP 2 LASTPIN (-7200 825) $PN 2
J 2
(-7210 835);
DISPLAY 0.808511 (-7210 835);
FORCEPROP 2 LAST VALUE DIFF BUS_0.22UF
J 2
(-7275 825);
DISPLAY 0.553191 (-7275 825);
FORCEPROP 2 LAST TOLERANCE 20%
J 2
(-7200 875);
DISPLAY 0.553191 (-7200 875);
DISPLAY INVISIBLE (-7200 875);
FORCEPROP 2 LAST PACK_TYPE C0201
J 2
(-7300 875);
DISPLAY 0.553191 (-7300 875);
DISPLAY INVISIBLE (-7300 875);
FORCEPROP 1 LAST MATERIAL X6S
J 2
(-7116 904);
DISPLAY 0.574468 (-7116 904);
PAINT GREEN (-7116 904);
DISPLAY INVISIBLE (-7116 904);
FORCEPROP 2 LAST VOLTAGE 6.3V
J 2
(-7475 875);
DISPLAY 0.553191 (-7475 875);
DISPLAY INVISIBLE (-7475 875);
FORCEPROP 1 LAST PIN_NAMES_ROTATE TRUE
J 2
(-7125 825);
DISPLAY 0.489362 (-7125 825);
PAINT GREEN (-7125 825);
DISPLAY INVISIBLE (-7125 825);
FORCEPROP 1 LAST CDS_LMAN_SYM_OUTLINE -25,50,25,-50
J 2
(-7125 825);
DISPLAY 0.468085 (-7125 825);
PAINT GREEN (-7125 825);
DISPLAY INVISIBLE (-7125 825);
FORCEPROP 2 LAST CDS_LIB pure_quanta
J 2
(-7125 825);
DISPLAY INVISIBLE (-7125 825);
FORCEPROP 1 LAST PATH I91
J 2
(-7125 825);
DISPLAY 0.723404 (-7125 825);
DISPLAY INVISIBLE (-7125 825);
FORCEPROP 1 LAST PART_NUMBER SP_CH4221MEE01
J 2
(-7241 913);
DISPLAY 0.574468 (-7241 913);
PAINT GREEN (-7241 913);
DISPLAY INVISIBLE (-7241 913);
FORCEPROP 1 LAST LOCATION C6593
J 0
(-6875 900);
DISPLAY 1.021277 (-6875 900);
DISPLAY INVISIBLE (-6875 900);
FORCEADD Q_CAP_DIFFBUS..2
R 2
(-7125 975);
FORCEPROP 1 LAST LOCATION C6592
J 2
(-6850 975);
DISPLAY 0.723404 (-6850 975);
PAINT GREEN (-6850 975);
FORCEPROP 2 LAST $SEC 1
J 2
(-6950 1050);
DISPLAY 0.680851 (-6950 1050);
PAINT MONO (-6950 1050);
DISPLAY INVISIBLE (-6950 1050);
FORCEPROP 2 LAST CDS_SEC 1
J 2
(-6950 1050);
DISPLAY 0.680851 (-6950 1050);
DISPLAY INVISIBLE (-6950 1050);
FORCEPROP 2 LASTPIN (-7050 975) $PN 1
J 0
(-7040 985);
DISPLAY 0.808511 (-7040 985);
FORCEPROP 2 LASTPIN (-7200 975) $PN 2
J 2
(-7210 985);
DISPLAY 0.808511 (-7210 985);
FORCEPROP 2 LAST VALUE DIFF BUS_0.22UF
J 2
(-7275 975);
DISPLAY 0.553191 (-7275 975);
FORCEPROP 2 LAST TOLERANCE 20%
J 2
(-7200 1025);
DISPLAY 0.553191 (-7200 1025);
DISPLAY INVISIBLE (-7200 1025);
FORCEPROP 2 LAST PACK_TYPE C0201
J 2
(-7300 1025);
DISPLAY 0.553191 (-7300 1025);
DISPLAY INVISIBLE (-7300 1025);
FORCEPROP 1 LAST MATERIAL X6S
J 2
(-7116 1054);
DISPLAY 0.574468 (-7116 1054);
PAINT GREEN (-7116 1054);
DISPLAY INVISIBLE (-7116 1054);
FORCEPROP 2 LAST VOLTAGE 6.3V
J 2
(-7475 1025);
DISPLAY 0.553191 (-7475 1025);
DISPLAY INVISIBLE (-7475 1025);
FORCEPROP 1 LAST PIN_NAMES_ROTATE TRUE
J 2
(-7125 975);
DISPLAY 0.489362 (-7125 975);
PAINT GREEN (-7125 975);
DISPLAY INVISIBLE (-7125 975);
FORCEPROP 2 LAST CDS_LIB pure_quanta
J 2
(-7125 975);
DISPLAY INVISIBLE (-7125 975);
FORCEPROP 1 LAST CDS_LMAN_SYM_OUTLINE -25,50,25,-50
J 2
(-7125 975);
DISPLAY 0.468085 (-7125 975);
PAINT GREEN (-7125 975);
DISPLAY INVISIBLE (-7125 975);
FORCEPROP 1 LAST PATH I92
J 2
(-7125 975);
DISPLAY 0.723404 (-7125 975);
DISPLAY INVISIBLE (-7125 975);
FORCEPROP 1 LAST PART_NUMBER SP_CH4221MEE01
J 2
(-7241 1063);
DISPLAY 0.574468 (-7241 1063);
PAINT GREEN (-7241 1063);
DISPLAY INVISIBLE (-7241 1063);
FORCEPROP 1 LAST LOCATION C6592
J 0
(-6875 1050);
DISPLAY 1.021277 (-6875 1050);
DISPLAY INVISIBLE (-6875 1050);
FORCEADD Q_CAP_DIFFBUS..2
R 2
(-7125 1025);
FORCEPROP 1 LAST LOCATION C6591
J 2
(-6850 1025);
DISPLAY 0.723404 (-6850 1025);
PAINT GREEN (-6850 1025);
FORCEPROP 2 LAST $SEC 1
J 2
(-6950 1100);
DISPLAY 0.680851 (-6950 1100);
PAINT MONO (-6950 1100);
DISPLAY INVISIBLE (-6950 1100);
FORCEPROP 2 LAST CDS_SEC 1
J 2
(-6950 1100);
DISPLAY 0.680851 (-6950 1100);
DISPLAY INVISIBLE (-6950 1100);
FORCEPROP 2 LASTPIN (-7050 1025) $PN 1
J 0
(-7040 1035);
DISPLAY 0.808511 (-7040 1035);
FORCEPROP 2 LASTPIN (-7200 1025) $PN 2
J 2
(-7210 1035);
DISPLAY 0.808511 (-7210 1035);
FORCEPROP 2 LAST VALUE DIFF BUS_0.22UF
J 2
(-7275 1025);
DISPLAY 0.553191 (-7275 1025);
FORCEPROP 2 LAST TOLERANCE 20%
J 2
(-7200 1075);
DISPLAY 0.553191 (-7200 1075);
DISPLAY INVISIBLE (-7200 1075);
FORCEPROP 2 LAST PACK_TYPE C0201
J 2
(-7300 1075);
DISPLAY 0.553191 (-7300 1075);
DISPLAY INVISIBLE (-7300 1075);
FORCEPROP 1 LAST MATERIAL X6S
J 2
(-7116 1104);
DISPLAY 0.574468 (-7116 1104);
PAINT GREEN (-7116 1104);
DISPLAY INVISIBLE (-7116 1104);
FORCEPROP 2 LAST VOLTAGE 6.3V
J 2
(-7475 1075);
DISPLAY 0.553191 (-7475 1075);
DISPLAY INVISIBLE (-7475 1075);
FORCEPROP 1 LAST PIN_NAMES_ROTATE TRUE
J 2
(-7125 1025);
DISPLAY 0.489362 (-7125 1025);
PAINT GREEN (-7125 1025);
DISPLAY INVISIBLE (-7125 1025);
FORCEPROP 2 LAST CDS_LIB pure_quanta
J 2
(-7125 1025);
DISPLAY INVISIBLE (-7125 1025);
FORCEPROP 1 LAST CDS_LMAN_SYM_OUTLINE -25,50,25,-50
J 2
(-7125 1025);
DISPLAY 0.468085 (-7125 1025);
PAINT GREEN (-7125 1025);
DISPLAY INVISIBLE (-7125 1025);
FORCEPROP 1 LAST PATH I93
J 2
(-7125 1025);
DISPLAY 0.723404 (-7125 1025);
DISPLAY INVISIBLE (-7125 1025);
FORCEPROP 1 LAST PART_NUMBER SP_CH4221MEE01
J 2
(-7241 1113);
DISPLAY 0.574468 (-7241 1113);
PAINT GREEN (-7241 1113);
DISPLAY INVISIBLE (-7241 1113);
FORCEPROP 1 LAST LOCATION C6591
J 0
(-6875 1100);
DISPLAY 1.021277 (-6875 1100);
DISPLAY INVISIBLE (-6875 1100);
FORCEADD Q_CAP_DIFFBUS..2
R 2
(-7125 1175);
FORCEPROP 1 LAST LOCATION C6590
J 2
(-6850 1175);
DISPLAY 0.723404 (-6850 1175);
PAINT GREEN (-6850 1175);
FORCEPROP 2 LAST $SEC 1
J 2
(-6950 1250);
DISPLAY 0.680851 (-6950 1250);
PAINT MONO (-6950 1250);
DISPLAY INVISIBLE (-6950 1250);
FORCEPROP 2 LAST CDS_SEC 1
J 2
(-6950 1250);
DISPLAY 0.680851 (-6950 1250);
DISPLAY INVISIBLE (-6950 1250);
FORCEPROP 2 LASTPIN (-7050 1175) $PN 1
J 0
(-7040 1185);
DISPLAY 0.808511 (-7040 1185);
FORCEPROP 2 LASTPIN (-7200 1175) $PN 2
J 2
(-7210 1185);
DISPLAY 0.808511 (-7210 1185);
FORCEPROP 2 LAST VALUE DIFF BUS_0.22UF
J 2
(-7275 1175);
DISPLAY 0.553191 (-7275 1175);
FORCEPROP 2 LAST TOLERANCE 20%
J 2
(-7200 1225);
DISPLAY 0.553191 (-7200 1225);
DISPLAY INVISIBLE (-7200 1225);
FORCEPROP 2 LAST PACK_TYPE C0201
J 2
(-7300 1225);
DISPLAY 0.553191 (-7300 1225);
DISPLAY INVISIBLE (-7300 1225);
FORCEPROP 1 LAST MATERIAL X6S
J 2
(-7116 1254);
DISPLAY 0.574468 (-7116 1254);
PAINT GREEN (-7116 1254);
DISPLAY INVISIBLE (-7116 1254);
FORCEPROP 2 LAST VOLTAGE 6.3V
J 2
(-7475 1225);
DISPLAY 0.553191 (-7475 1225);
DISPLAY INVISIBLE (-7475 1225);
FORCEPROP 1 LAST PIN_NAMES_ROTATE TRUE
J 2
(-7125 1175);
DISPLAY 0.489362 (-7125 1175);
PAINT GREEN (-7125 1175);
DISPLAY INVISIBLE (-7125 1175);
FORCEPROP 1 LAST CDS_LMAN_SYM_OUTLINE -25,50,25,-50
J 2
(-7125 1175);
DISPLAY 0.468085 (-7125 1175);
PAINT GREEN (-7125 1175);
DISPLAY INVISIBLE (-7125 1175);
FORCEPROP 2 LAST CDS_LIB pure_quanta
J 2
(-7125 1175);
DISPLAY INVISIBLE (-7125 1175);
FORCEPROP 1 LAST PATH I94
J 2
(-7125 1175);
DISPLAY 0.723404 (-7125 1175);
DISPLAY INVISIBLE (-7125 1175);
FORCEPROP 1 LAST PART_NUMBER SP_CH4221MEE01
J 2
(-7241 1263);
DISPLAY 0.574468 (-7241 1263);
PAINT GREEN (-7241 1263);
DISPLAY INVISIBLE (-7241 1263);
FORCEPROP 1 LAST LOCATION C6590
J 0
(-6875 1250);
DISPLAY 1.021277 (-6875 1250);
DISPLAY INVISIBLE (-6875 1250);
FORCEADD Q_CAP_DIFFBUS..2
R 2
(-7125 1225);
FORCEPROP 1 LAST LOCATION C6589
J 2
(-6850 1225);
DISPLAY 0.723404 (-6850 1225);
PAINT GREEN (-6850 1225);
FORCEPROP 2 LAST $SEC 1
J 2
(-6950 1300);
DISPLAY 0.680851 (-6950 1300);
PAINT MONO (-6950 1300);
DISPLAY INVISIBLE (-6950 1300);
FORCEPROP 2 LAST CDS_SEC 1
J 2
(-6950 1300);
DISPLAY 0.680851 (-6950 1300);
DISPLAY INVISIBLE (-6950 1300);
FORCEPROP 2 LASTPIN (-7050 1225) $PN 1
J 0
(-7040 1235);
DISPLAY 0.808511 (-7040 1235);
FORCEPROP 2 LASTPIN (-7200 1225) $PN 2
J 2
(-7210 1235);
DISPLAY 0.808511 (-7210 1235);
FORCEPROP 2 LAST VALUE DIFF BUS_0.22UF
J 2
(-7275 1225);
DISPLAY 0.553191 (-7275 1225);
FORCEPROP 2 LAST TOLERANCE 20%
J 2
(-7200 1275);
DISPLAY 0.553191 (-7200 1275);
DISPLAY INVISIBLE (-7200 1275);
FORCEPROP 2 LAST PACK_TYPE C0201
J 2
(-7300 1275);
DISPLAY 0.553191 (-7300 1275);
DISPLAY INVISIBLE (-7300 1275);
FORCEPROP 1 LAST MATERIAL X6S
J 2
(-7116 1304);
DISPLAY 0.574468 (-7116 1304);
PAINT GREEN (-7116 1304);
DISPLAY INVISIBLE (-7116 1304);
FORCEPROP 2 LAST VOLTAGE 6.3V
J 2
(-7475 1275);
DISPLAY 0.553191 (-7475 1275);
DISPLAY INVISIBLE (-7475 1275);
FORCEPROP 1 LAST PIN_NAMES_ROTATE TRUE
J 2
(-7125 1225);
DISPLAY 0.489362 (-7125 1225);
PAINT GREEN (-7125 1225);
DISPLAY INVISIBLE (-7125 1225);
FORCEPROP 1 LAST CDS_LMAN_SYM_OUTLINE -25,50,25,-50
J 2
(-7125 1225);
DISPLAY 0.468085 (-7125 1225);
PAINT GREEN (-7125 1225);
DISPLAY INVISIBLE (-7125 1225);
FORCEPROP 2 LAST CDS_LIB pure_quanta
J 2
(-7125 1225);
DISPLAY INVISIBLE (-7125 1225);
FORCEPROP 1 LAST PATH I95
J 2
(-7125 1225);
DISPLAY 0.723404 (-7125 1225);
DISPLAY INVISIBLE (-7125 1225);
FORCEPROP 1 LAST PART_NUMBER SP_CH4221MEE01
J 2
(-7241 1313);
DISPLAY 0.574468 (-7241 1313);
PAINT GREEN (-7241 1313);
DISPLAY INVISIBLE (-7241 1313);
FORCEPROP 1 LAST LOCATION C6589
J 0
(-6875 1300);
DISPLAY 1.021277 (-6875 1300);
DISPLAY INVISIBLE (-6875 1300);
FORCEADD Q_CAP_DIFFBUS..2
R 2
(-7125 1375);
FORCEPROP 1 LAST LOCATION C6588
J 2
(-6850 1375);
DISPLAY 0.723404 (-6850 1375);
PAINT GREEN (-6850 1375);
FORCEPROP 2 LAST $SEC 1
J 2
(-6950 1450);
DISPLAY 0.680851 (-6950 1450);
PAINT MONO (-6950 1450);
DISPLAY INVISIBLE (-6950 1450);
FORCEPROP 2 LAST CDS_SEC 1
J 2
(-6950 1450);
DISPLAY 0.680851 (-6950 1450);
DISPLAY INVISIBLE (-6950 1450);
FORCEPROP 2 LASTPIN (-7050 1375) $PN 1
J 0
(-7040 1385);
DISPLAY 0.808511 (-7040 1385);
FORCEPROP 2 LASTPIN (-7200 1375) $PN 2
J 2
(-7210 1385);
DISPLAY 0.808511 (-7210 1385);
FORCEPROP 2 LAST VALUE DIFF BUS_0.22UF
J 2
(-7275 1375);
DISPLAY 0.553191 (-7275 1375);
FORCEPROP 2 LAST TOLERANCE 20%
J 2
(-7200 1425);
DISPLAY 0.553191 (-7200 1425);
DISPLAY INVISIBLE (-7200 1425);
FORCEPROP 2 LAST PACK_TYPE C0201
J 2
(-7300 1425);
DISPLAY 0.553191 (-7300 1425);
DISPLAY INVISIBLE (-7300 1425);
FORCEPROP 1 LAST MATERIAL X6S
J 2
(-7116 1454);
DISPLAY 0.574468 (-7116 1454);
PAINT GREEN (-7116 1454);
DISPLAY INVISIBLE (-7116 1454);
FORCEPROP 2 LAST VOLTAGE 6.3V
J 2
(-7475 1425);
DISPLAY 0.553191 (-7475 1425);
DISPLAY INVISIBLE (-7475 1425);
FORCEPROP 1 LAST PIN_NAMES_ROTATE TRUE
J 2
(-7125 1375);
DISPLAY 0.489362 (-7125 1375);
PAINT GREEN (-7125 1375);
DISPLAY INVISIBLE (-7125 1375);
FORCEPROP 2 LAST CDS_LIB pure_quanta
J 2
(-7125 1375);
DISPLAY INVISIBLE (-7125 1375);
FORCEPROP 1 LAST CDS_LMAN_SYM_OUTLINE -25,50,25,-50
J 2
(-7125 1375);
DISPLAY 0.468085 (-7125 1375);
PAINT GREEN (-7125 1375);
DISPLAY INVISIBLE (-7125 1375);
FORCEPROP 1 LAST PATH I96
J 2
(-7125 1375);
DISPLAY 0.723404 (-7125 1375);
DISPLAY INVISIBLE (-7125 1375);
FORCEPROP 1 LAST PART_NUMBER SP_CH4221MEE01
J 2
(-7241 1463);
DISPLAY 0.574468 (-7241 1463);
PAINT GREEN (-7241 1463);
DISPLAY INVISIBLE (-7241 1463);
FORCEPROP 1 LAST LOCATION C6588
J 0
(-6875 1450);
DISPLAY 1.021277 (-6875 1450);
DISPLAY INVISIBLE (-6875 1450);
FORCEADD Q_CAP_DIFFBUS..2
R 2
(-7125 1425);
FORCEPROP 1 LAST LOCATION C6587
J 2
(-6850 1425);
DISPLAY 0.723404 (-6850 1425);
PAINT GREEN (-6850 1425);
FORCEPROP 2 LAST $SEC 1
J 2
(-6950 1500);
DISPLAY 0.680851 (-6950 1500);
PAINT MONO (-6950 1500);
DISPLAY INVISIBLE (-6950 1500);
FORCEPROP 2 LAST CDS_SEC 1
J 2
(-6950 1500);
DISPLAY 0.680851 (-6950 1500);
DISPLAY INVISIBLE (-6950 1500);
FORCEPROP 2 LASTPIN (-7050 1425) $PN 1
J 0
(-7040 1435);
DISPLAY 0.808511 (-7040 1435);
FORCEPROP 2 LASTPIN (-7200 1425) $PN 2
J 2
(-7210 1435);
DISPLAY 0.808511 (-7210 1435);
FORCEPROP 2 LAST VALUE DIFF BUS_0.22UF
J 2
(-7275 1425);
DISPLAY 0.553191 (-7275 1425);
FORCEPROP 2 LAST TOLERANCE 20%
J 2
(-7200 1475);
DISPLAY 0.553191 (-7200 1475);
DISPLAY INVISIBLE (-7200 1475);
FORCEPROP 2 LAST PACK_TYPE C0201
J 2
(-7300 1475);
DISPLAY 0.553191 (-7300 1475);
DISPLAY INVISIBLE (-7300 1475);
FORCEPROP 1 LAST MATERIAL X6S
J 2
(-7116 1504);
DISPLAY 0.574468 (-7116 1504);
PAINT GREEN (-7116 1504);
DISPLAY INVISIBLE (-7116 1504);
FORCEPROP 2 LAST VOLTAGE 6.3V
J 2
(-7475 1475);
DISPLAY 0.553191 (-7475 1475);
DISPLAY INVISIBLE (-7475 1475);
FORCEPROP 1 LAST PIN_NAMES_ROTATE TRUE
J 2
(-7125 1425);
DISPLAY 0.489362 (-7125 1425);
PAINT GREEN (-7125 1425);
DISPLAY INVISIBLE (-7125 1425);
FORCEPROP 2 LAST CDS_LIB pure_quanta
J 2
(-7125 1425);
DISPLAY INVISIBLE (-7125 1425);
FORCEPROP 1 LAST CDS_LMAN_SYM_OUTLINE -25,50,25,-50
J 2
(-7125 1425);
DISPLAY 0.468085 (-7125 1425);
PAINT GREEN (-7125 1425);
DISPLAY INVISIBLE (-7125 1425);
FORCEPROP 1 LAST PATH I97
J 2
(-7125 1425);
DISPLAY 0.723404 (-7125 1425);
DISPLAY INVISIBLE (-7125 1425);
FORCEPROP 1 LAST PART_NUMBER SP_CH4221MEE01
J 2
(-7241 1513);
DISPLAY 0.574468 (-7241 1513);
PAINT GREEN (-7241 1513);
DISPLAY INVISIBLE (-7241 1513);
FORCEPROP 1 LAST LOCATION C6587
J 0
(-6875 1500);
DISPLAY 1.021277 (-6875 1500);
DISPLAY INVISIBLE (-6875 1500);
FORCEADD Q_CAP_DIFFBUS..2
R 2
(-7125 1575);
FORCEPROP 1 LAST LOCATION C6586
J 2
(-6850 1575);
DISPLAY 0.723404 (-6850 1575);
PAINT GREEN (-6850 1575);
FORCEPROP 2 LAST $SEC 1
J 2
(-6950 1650);
DISPLAY 0.680851 (-6950 1650);
PAINT MONO (-6950 1650);
DISPLAY INVISIBLE (-6950 1650);
FORCEPROP 2 LAST CDS_SEC 1
J 2
(-6950 1650);
DISPLAY 0.680851 (-6950 1650);
DISPLAY INVISIBLE (-6950 1650);
FORCEPROP 2 LASTPIN (-7050 1575) $PN 1
J 0
(-7040 1585);
DISPLAY 0.808511 (-7040 1585);
FORCEPROP 2 LASTPIN (-7200 1575) $PN 2
J 2
(-7210 1585);
DISPLAY 0.808511 (-7210 1585);
FORCEPROP 2 LAST VALUE DIFF BUS_0.22UF
J 2
(-7275 1575);
DISPLAY 0.553191 (-7275 1575);
FORCEPROP 2 LAST TOLERANCE 20%
J 2
(-7200 1625);
DISPLAY 0.553191 (-7200 1625);
DISPLAY INVISIBLE (-7200 1625);
FORCEPROP 2 LAST PACK_TYPE C0201
J 2
(-7300 1625);
DISPLAY 0.553191 (-7300 1625);
DISPLAY INVISIBLE (-7300 1625);
FORCEPROP 1 LAST MATERIAL X6S
J 2
(-7116 1654);
DISPLAY 0.574468 (-7116 1654);
PAINT GREEN (-7116 1654);
DISPLAY INVISIBLE (-7116 1654);
FORCEPROP 2 LAST VOLTAGE 6.3V
J 2
(-7475 1625);
DISPLAY 0.553191 (-7475 1625);
DISPLAY INVISIBLE (-7475 1625);
FORCEPROP 1 LAST PIN_NAMES_ROTATE TRUE
J 2
(-7125 1575);
DISPLAY 0.489362 (-7125 1575);
PAINT GREEN (-7125 1575);
DISPLAY INVISIBLE (-7125 1575);
FORCEPROP 2 LAST CDS_LIB pure_quanta
J 2
(-7125 1575);
DISPLAY INVISIBLE (-7125 1575);
FORCEPROP 1 LAST CDS_LMAN_SYM_OUTLINE -25,50,25,-50
J 2
(-7125 1575);
DISPLAY 0.468085 (-7125 1575);
PAINT GREEN (-7125 1575);
DISPLAY INVISIBLE (-7125 1575);
FORCEPROP 1 LAST PATH I98
J 2
(-7125 1575);
DISPLAY 0.723404 (-7125 1575);
DISPLAY INVISIBLE (-7125 1575);
FORCEPROP 1 LAST PART_NUMBER SP_CH4221MEE01
J 2
(-7241 1663);
DISPLAY 0.574468 (-7241 1663);
PAINT GREEN (-7241 1663);
DISPLAY INVISIBLE (-7241 1663);
FORCEPROP 1 LAST LOCATION C6586
J 0
(-6875 1650);
DISPLAY 1.021277 (-6875 1650);
DISPLAY INVISIBLE (-6875 1650);
FORCEADD Q_CAP_DIFFBUS..2
R 2
(-7125 1625);
FORCEPROP 1 LAST LOCATION C6585
J 2
(-6850 1625);
DISPLAY 0.723404 (-6850 1625);
PAINT GREEN (-6850 1625);
FORCEPROP 2 LAST $SEC 1
J 2
(-6950 1700);
DISPLAY 0.680851 (-6950 1700);
PAINT MONO (-6950 1700);
DISPLAY INVISIBLE (-6950 1700);
FORCEPROP 2 LAST CDS_SEC 1
J 2
(-6950 1700);
DISPLAY 0.680851 (-6950 1700);
DISPLAY INVISIBLE (-6950 1700);
FORCEPROP 2 LASTPIN (-7050 1625) $PN 1
J 0
(-7040 1635);
DISPLAY 0.808511 (-7040 1635);
FORCEPROP 2 LASTPIN (-7200 1625) $PN 2
J 2
(-7210 1635);
DISPLAY 0.808511 (-7210 1635);
FORCEPROP 2 LAST VALUE DIFF BUS_0.22UF
J 2
(-7275 1625);
DISPLAY 0.553191 (-7275 1625);
FORCEPROP 2 LAST TOLERANCE 20%
J 2
(-7200 1675);
DISPLAY 0.553191 (-7200 1675);
DISPLAY INVISIBLE (-7200 1675);
FORCEPROP 2 LAST PACK_TYPE C0201
J 2
(-7300 1675);
DISPLAY 0.553191 (-7300 1675);
DISPLAY INVISIBLE (-7300 1675);
FORCEPROP 1 LAST MATERIAL X6S
J 2
(-7116 1704);
DISPLAY 0.574468 (-7116 1704);
PAINT GREEN (-7116 1704);
DISPLAY INVISIBLE (-7116 1704);
FORCEPROP 2 LAST VOLTAGE 6.3V
J 2
(-7475 1675);
DISPLAY 0.553191 (-7475 1675);
DISPLAY INVISIBLE (-7475 1675);
FORCEPROP 1 LAST PIN_NAMES_ROTATE TRUE
J 2
(-7125 1625);
DISPLAY 0.489362 (-7125 1625);
PAINT GREEN (-7125 1625);
DISPLAY INVISIBLE (-7125 1625);
FORCEPROP 2 LAST CDS_LIB pure_quanta
J 2
(-7125 1625);
DISPLAY INVISIBLE (-7125 1625);
FORCEPROP 1 LAST CDS_LMAN_SYM_OUTLINE -25,50,25,-50
J 2
(-7125 1625);
DISPLAY 0.468085 (-7125 1625);
PAINT GREEN (-7125 1625);
DISPLAY INVISIBLE (-7125 1625);
FORCEPROP 1 LAST PATH I99
J 2
(-7125 1625);
DISPLAY 0.723404 (-7125 1625);
DISPLAY INVISIBLE (-7125 1625);
FORCEPROP 1 LAST PART_NUMBER SP_CH4221MEE01
J 2
(-7241 1713);
DISPLAY 0.574468 (-7241 1713);
PAINT GREEN (-7241 1713);
DISPLAY INVISIBLE (-7241 1713);
FORCEPROP 1 LAST LOCATION C6585
J 0
(-6875 1700);
DISPLAY 1.021277 (-6875 1700);
DISPLAY INVISIBLE (-6875 1700);
FORCEADD QUANTA_TITLE_BLOCK_C..1
(0 0);
FORCEPROP 0 LAST CDS_CON_LAST_MODIFIED Thu Sep 14 16:12:53 2023
J 0
(-1885 15);
DISPLAY INVISIBLE (-1885 15);
FORCEPROP 1 LAST CUSTOM_TXT_CDS <CON_LAST_MODIFIED>
J 0
(-1885 15);
DISPLAY 0.978723 (-1885 15);
FORCEPROP 2 LAST CUSTOM_TXT_CDS <XR_PAGE_TITLE>
J 0
(-7890 5250);
DISPLAY 0.638298 (-7890 5250);
PAINT PINK (-7890 5250);
DISPLAY INVISIBLE (-7890 5250);
FORCEPROP 1 LAST CUSTOM_TXT_CDS <NAME_2>
J 0
(-3175 50);
FORCEPROP 1 LAST CUSTOM_TXT_CDS <NAME_1>
J 0
(-3175 175);
FORCEPROP 1 LAST CUSTOM_TXT_CDS <Q_NUMBER>
J 0
(-1403 103);
DISPLAY 1.212766 (-1403 103);
FORCEPROP 1 LAST CUSTOM_TXT_CDS <Q_PROJ>
J 0
(-2382 102);
DISPLAY 1.212766 (-2382 102);
FORCEPROP 1 LAST CUSTOM_TXT_CDS <Q_REV>
J 0
(-184 103);
DISPLAY 1.212766 (-184 103);
FORCEPROP 1 LAST CUSTOM_TXT_CDS <CON_PAGE_NUM> OF <CON_TOTAL_PAGES>
J 0
(-446 18);
DISPLAY 0.978723 (-446 18);
FORCEPROP 1 LAST Q_TITLE RETIMER_CPU0_P2(4)
J 0
(-9366 26);
DISPLAY 2.446809 (-9366 26);
PAINT GREEN (-9366 26);
FORCEPROP 2 LAST PAGE_BORDER TRUE
J 0
(-7890 5250);
DISPLAY 0.638298 (-7890 5250);
PAINT PINK (-7890 5250);
DISPLAY INVISIBLE (-7890 5250);
FORCEPROP 1 LAST CDS_LMAN_SYM_OUTLINE -9475,6775,100,-125
J 0
(0 0);
DISPLAY 0.468085 (0 0);
PAINT GREEN (0 0);
DISPLAY INVISIBLE (0 0);
FORCEPROP 2 LAST CDS_LIB pure_quanta
J 0
(0 0);
DISPLAY INVISIBLE (0 0);
FORCEPROP 2 LAST CDS_XR_PAGE_TITLE CR-298 : @T6G_MB_LIB.T6G(SCH_1):PAGE298
J 0
(-7890 5250);
DISPLAY 0.638298 (-7890 5250);
PAINT PINK (-7890 5250);
DISPLAY INVISIBLE (-7890 5250);
FORCEPROP 1 LAST Q_DEPT BU9
J 1
(-3763 49);
DISPLAY 1.957447 (-3763 49);
PAINT GREEN (-3763 49);
DISPLAY INVISIBLE (-3763 49);
FORCEPROP 1 LAST COMMENT_BODY TRUE
J 0
(12 -13);
DISPLAY 0.978723 (12 -13);
PAINT GREEN (12 -13);
DISPLAY INVISIBLE (12 -13);
WIRE 17 -1 (-6850 3800)(-6850 3450);
WIRE 17 -1 (-6850 4150)(-6850 3800);
WIRE 17 -1 (-6850 3450)(-6850 3100);
WIRE 17 -1 (-6850 4150)(-6850 4500);
WIRE 17 -1 (-6850 4850)(-6850 4500);
WIRE 17 -1 (-6850 5200)(-6850 4850);
WIRE 17 -1 (-6850 5550)(-6850 5200);
FORCEPROP 2 LAST SIG_NAME P5E_CPU0_P2_TX_BUF_DN<15:8>
J 0
(-6860 5560);
DISPLAY 0.680851 (-6860 5560);
PAINT WHITE (-6860 5560);
WIRE 17 -1 (-3300 525)(-3300 725);
WIRE 17 -1 (-3300 725)(-3300 925);
WIRE 17 -1 (-3300 925)(-3300 1125);
WIRE 17 -1 (-3300 1125)(-3300 1325);
WIRE 17 -1 (-3300 1325)(-3300 1525);
WIRE 17 -1 (-3300 1525)(-3300 1725);
WIRE 17 -1 (-3300 1725)(-3300 1925);
WIRE 17 -1 (-4150 1925)(-3300 1925);
FORCEPROP 2 LAST SIG_NAME P5E_CPU0_P2_TX_BUF_DN<7:0>
J 0
(-4135 1935);
DISPLAY 0.680851 (-4135 1935);
PAINT WHITE (-4135 1935);
WIRE 17 -1 (-3050 775)(-3050 575);
WIRE 17 -1 (-3050 975)(-3050 775);
WIRE 17 -1 (-3050 1175)(-3050 975);
WIRE 17 -1 (-3050 1175)(-3050 1375);
WIRE 17 -1 (-3050 1575)(-3050 1375);
WIRE 17 -1 (-3050 1775)(-3050 1575);
WIRE 17 -1 (-3050 1975)(-3050 1775);
WIRE 17 -1 (-4150 1975)(-3050 1975);
FORCEPROP 2 LAST SIG_NAME P5E_CPU0_P2_TX_BUF_DP<7:0>
J 0
(-4135 1985);
DISPLAY 0.680851 (-4135 1985);
PAINT WHITE (-4135 1985);
WIRE 17 -1 (-1675 775)(-1675 575);
WIRE 17 -1 (-1675 975)(-1675 775);
WIRE 17 -1 (-1675 1175)(-1675 975);
WIRE 17 -1 (-1675 1175)(-1675 1375);
WIRE 17 -1 (-1675 1575)(-1675 1375);
WIRE 17 -1 (-1675 1775)(-1675 1575);
WIRE 17 -1 (-1675 1975)(-1675 1775);
WIRE 17 -1 (-1675 1975)(-575 1975);
FORCEPROP 2 LAST SIG_NAME P5E_CPU0_P2_TX_BUF_C_DP<7:0>
J 0
(-1485 1985);
DISPLAY 0.680851 (-1485 1985);
PAINT WHITE (-1485 1985);
WIRE 17 -1 (-1475 725)(-1475 525);
WIRE 17 -1 (-1475 925)(-1475 725);
WIRE 17 -1 (-1475 1125)(-1475 925);
WIRE 17 -1 (-1475 1125)(-1475 1325);
WIRE 17 -1 (-1475 1525)(-1475 1325);
WIRE 17 -1 (-1475 1725)(-1475 1525);
WIRE 17 -1 (-1475 1925)(-1475 1725);
FORCEPROP 2 LAST SIG_NAME P5E_CPU0_P2_TX_BUF_C_DN<7:0>
J 0
(-1485 1935);
DISPLAY 0.680851 (-1485 1935);
PAINT WHITE (-1485 1935);
WIRE 17 -1 (-6325 2000)(-6325 1800);
WIRE 17 -1 (-6325 2000)(-5425 2000);
FORCEPROP 2 LAST SIG_NAME P5E_CPU0_P2_TX_BUF_C_DN<15:8>
J 0
(-6335 2010);
DISPLAY 0.680851 (-6335 2010);
PAINT WHITE (-6335 2010);
WIRE 17 -1 (-8150 600)(-8150 800);
WIRE 17 -1 (-8150 800)(-8150 1000);
WIRE 17 -1 (-8150 1000)(-8150 1200);
WIRE 17 -1 (-8150 1200)(-8150 1400);
WIRE 17 -1 (-8150 1400)(-8150 1600);
WIRE 17 -1 (-8150 1600)(-8150 1800);
WIRE 17 -1 (-8150 1800)(-8150 2000);
WIRE 17 -1 (-9000 2000)(-8150 2000);
FORCEPROP 2 LAST SIG_NAME P5E_CPU0_P2_TX_BUF_DN<15:8>
J 0
(-8985 2010);
DISPLAY 0.680851 (-8985 2010);
PAINT WHITE (-8985 2010);
WIRE 17 -1 (-7900 850)(-7900 650);
WIRE 17 -1 (-7900 1050)(-7900 850);
WIRE 17 -1 (-7900 1250)(-7900 1050);
WIRE 17 -1 (-7900 1250)(-7900 1450);
WIRE 17 -1 (-7900 1650)(-7900 1450);
WIRE 17 -1 (-7900 1850)(-7900 1650);
WIRE 17 -1 (-7900 2050)(-7900 1850);
WIRE 17 -1 (-9000 2050)(-7900 2050);
FORCEPROP 2 LAST SIG_NAME P5E_CPU0_P2_TX_BUF_DP<15:8>
J 0
(-8985 2060);
DISPLAY 0.680851 (-8985 2060);
PAINT WHITE (-8985 2060);
WIRE 17 -1 (-6325 800)(-6325 600);
WIRE 17 -1 (-6325 1000)(-6325 800);
WIRE 17 -1 (-6325 1200)(-6325 1000);
WIRE 17 -1 (-6325 1200)(-6325 1400);
WIRE 17 -1 (-6325 1600)(-6325 1400);
WIRE 17 -1 (-6325 1800)(-6325 1600);
WIRE 17 -1 (-6525 1050)(-6525 850);
WIRE 17 -1 (-6525 1250)(-6525 1050);
WIRE 17 -1 (-6525 850)(-6525 650);
WIRE 17 -1 (-6525 1250)(-6525 1450);
WIRE 17 -1 (-6525 1650)(-6525 1450);
WIRE 17 -1 (-6525 1850)(-6525 1650);
WIRE 17 -1 (-6525 2050)(-6525 1850);
WIRE 17 -1 (-6525 2050)(-5425 2050);
FORCEPROP 2 LAST SIG_NAME P5E_CPU0_P2_TX_BUF_C_DP<15:8>
J 0
(-6335 2060);
DISPLAY 0.680851 (-6335 2060);
PAINT WHITE (-6335 2060);
WIRE 17 -1 (-7050 5650)(-5950 5650);
FORCEPROP 2 LAST SIG_NAME P5E_CPU0_P2_TX_BUF_DP<15:8>
J 0
(-6860 5660);
DISPLAY 0.680851 (-6860 5660);
PAINT WHITE (-6860 5660);
WIRE 17 -1 (-1675 4825)(-1675 4475);
WIRE 17 -1 (-1675 5175)(-1675 4825);
WIRE 17 -1 (-1675 4125)(-1675 4475);
WIRE 17 -1 (-1675 4125)(-1675 3775);
WIRE 17 -1 (-1675 5525)(-1675 5175);
FORCEPROP 2 LAST SIG_NAME P5E_CPU0_P2_TX_BUF_DN<7:0>
J 0
(-1685 5535);
DISPLAY 0.680851 (-1685 5535);
PAINT WHITE (-1685 5535);
WIRE 17 -1 (-1875 5275)(-1875 4925);
WIRE 17 -1 (-1875 5625)(-1875 5275);
WIRE 17 -1 (-1875 4925)(-1875 4575);
WIRE 17 -1 (-1875 4225)(-1875 4575);
WIRE 17 -1 (-1875 5625)(-775 5625);
FORCEPROP 2 LAST SIG_NAME P5E_CPU0_P2_TX_BUF_DP<7:0>
J 0
(-1685 5635);
DISPLAY 0.680851 (-1685 5635);
PAINT WHITE (-1685 5635);
WIRE 17 -1 (-1675 3775)(-1675 3425);
WIRE 17 -1 (-1675 3425)(-1675 3075);
WIRE 17 -1 (-1875 3525)(-1875 3175);
WIRE 17 -1 (-1875 3875)(-1875 3525);
WIRE 17 -1 (-1875 4225)(-1875 3875);
WIRE 17 -1 (-7050 3550)(-7050 3200);
WIRE 17 -1 (-7050 3900)(-7050 3550);
WIRE 17 -1 (-7050 4250)(-7050 3900);
WIRE 17 -1 (-7050 4250)(-7050 4600);
WIRE 17 -1 (-7050 4950)(-7050 4600);
WIRE 17 -1 (-7050 5300)(-7050 4950);
WIRE 17 -1 (-7050 5650)(-7050 5300);
WIRE 17 -1 (-6850 5550)(-5975 5550);
WIRE 17 -1 (-1475 1925)(-575 1925);
WIRE 17 -1 (-1675 5525)(-800 5525);
WIRE 16 -1 (-7375 3525)(-7150 3525);
WIRE 16 -1 (-7375 4825)(-6950 4825);
WIRE 16 -1 (-7375 4575)(-7150 4575);
WIRE 16 -1 (-7375 4475)(-6950 4475);
WIRE 16 -1 (-7375 4225)(-7150 4225);
WIRE 16 -1 (-7375 4925)(-7150 4925);
WIRE 16 -1 (-7375 5175)(-6950 5175);
WIRE 16 -1 (-7375 5275)(-7150 5275);
WIRE 16 -1 (-2200 3850)(-1975 3850);
WIRE 16 -1 (-2200 3500)(-1975 3500);
WIRE 16 -1 (-2200 3050)(-1775 3050);
WIRE 16 -1 (-2200 4100)(-1775 4100);
WIRE 16 -1 (-2200 4550)(-1975 4550);
WIRE 16 -1 (-2200 4200)(-1975 4200);
WIRE 16 -1 (-7375 3875)(-7150 3875);
WIRE 16 -1 (-2200 5150)(-1775 5150);
WIRE 16 -1 (-7375 3175)(-7150 3175);
WIRE 16 -1 (-7375 3775)(-6950 3775);
WIRE 16 -1 (-7375 4125)(-6950 4125);
WIRE 16 -1 (-7375 3075)(-6950 3075);
WIRE 16 -1 (-7375 5525)(-6950 5525);
WIRE 16 -1 (-2200 5250)(-1975 5250);
WIRE 16 -1 (-2200 3150)(-1975 3150);
WIRE 16 -1 (-2200 3400)(-1775 3400);
WIRE 16 -1 (-2200 3750)(-1775 3750);
WIRE 16 -1 (-2200 5600)(-1975 5600);
WIRE 16 -1 (-2200 5500)(-1775 5500);
WIRE 16 -1 (-2200 4900)(-1975 4900);
WIRE 16 -1 (-2200 4800)(-1775 4800);
WIRE 16 -1 (-2200 4450)(-1775 4450);
WIRE 16 -1 (-7375 5625)(-7150 5625);
WIRE 16 -1 (-7050 1825)(-6625 1825);
WIRE 16 -1 (-7050 2025)(-6625 2025);
WIRE 16 -1 (-7050 1975)(-6425 1975);
WIRE 16 -1 (-7050 1625)(-6625 1625);
WIRE 16 -1 (-7050 1425)(-6625 1425);
WIRE 16 -1 (-7050 1575)(-6425 1575);
WIRE 16 -1 (-7050 1375)(-6425 1375);
WIRE 16 -1 (-7050 1175)(-6425 1175);
WIRE 16 -1 (-7050 1225)(-6625 1225);
WIRE 16 -1 (-7050 975)(-6425 975);
WIRE 16 -1 (-7050 1025)(-6625 1025);
WIRE 16 -1 (-7050 625)(-6625 625);
WIRE 16 -1 (-7050 775)(-6425 775);
WIRE 16 -1 (-7050 825)(-6625 825);
WIRE 16 -1 (-7050 575)(-6425 575);
WIRE 16 -1 (-7200 2025)(-7800 2025);
WIRE 16 -1 (-7200 1825)(-7800 1825);
WIRE 16 -1 (-7200 1625)(-7800 1625);
WIRE 16 -1 (-7200 1975)(-8050 1975);
WIRE 16 -1 (-7200 1775)(-8050 1775);
WIRE 16 -1 (-7200 1425)(-7800 1425);
WIRE 16 -1 (-7200 1225)(-7800 1225);
WIRE 16 -1 (-7200 1575)(-8050 1575);
WIRE 16 -1 (-7200 1375)(-8050 1375);
WIRE 16 -1 (-7200 1175)(-8050 1175);
WIRE 16 -1 (-7200 1025)(-7800 1025);
WIRE 16 -1 (-7200 825)(-7800 825);
WIRE 16 -1 (-7200 625)(-7800 625);
WIRE 16 -1 (-7200 975)(-8050 975);
WIRE 16 -1 (-7200 775)(-8050 775);
WIRE 16 -1 (-7200 575)(-8050 575);
WIRE 16 -1 (-7050 1775)(-6425 1775);
WIRE 16 -1 (-2200 1700)(-1575 1700);
WIRE 16 -1 (-2200 1750)(-1775 1750);
WIRE 16 -1 (-2200 1950)(-1775 1950);
WIRE 16 -1 (-2200 1900)(-1575 1900);
WIRE 16 -1 (-2200 1500)(-1575 1500);
WIRE 16 -1 (-2200 1550)(-1775 1550);
WIRE 16 -1 (-2350 1950)(-2950 1950);
WIRE 16 -1 (-2350 1750)(-2950 1750);
WIRE 16 -1 (-2350 1550)(-2950 1550);
WIRE 16 -1 (-2350 1700)(-3200 1700);
WIRE 16 -1 (-2350 1900)(-3200 1900);
WIRE 16 -1 (-2350 1500)(-3200 1500);
WIRE 16 -1 (-2200 1350)(-1775 1350);
WIRE 16 -1 (-2200 1300)(-1575 1300);
WIRE 16 -1 (-2200 1150)(-1775 1150);
WIRE 16 -1 (-2200 1100)(-1575 1100);
WIRE 16 -1 (-2200 950)(-1775 950);
WIRE 16 -1 (-2200 900)(-1575 900);
WIRE 16 -1 (-2200 750)(-1775 750);
WIRE 16 -1 (-2200 700)(-1575 700);
WIRE 16 -1 (-2200 500)(-1575 500);
WIRE 16 -1 (-2200 550)(-1775 550);
WIRE 16 -1 (-2350 1350)(-2950 1350);
WIRE 16 -1 (-2350 950)(-2950 950);
WIRE 16 -1 (-2350 1150)(-2950 1150);
WIRE 16 -1 (-2350 1300)(-3200 1300);
WIRE 16 -1 (-2350 1100)(-3200 1100);
WIRE 16 -1 (-2350 750)(-2950 750);
WIRE 16 -1 (-2350 550)(-2950 550);
WIRE 16 -1 (-2350 900)(-3200 900);
WIRE 16 -1 (-2350 700)(-3200 700);
WIRE 16 -1 (-2350 500)(-3200 500);
WIRE 16 -1 (-7375 3425)(-6950 3425);
FORCENOTE
RETIMER TO EXAMAX
(-8725 2725) 0;
DISPLAY LEFT (-8725 2725);
DISPLAY 3.148936 (-8725 2725);
FORCENOTE
RETIMER TO EXAMAX
(-3725 2700) 0;
DISPLAY LEFT (-3725 2700);
DISPLAY 3.148936 (-3725 2700);
FORCENOTE
P5E_CPU0_P2_TX_BUF_DP/DN <0-15> LANE REVERSAL
(-9200 6325) 0;
DISPLAY LEFT (-9200 6325);
DISPLAY 1.595745 (-9200 6325);
QUIT
